FILE_TYPE = MACRO_DRAWING;
SET COLOR_WIRE YELLOW;
SET COLOR_PROP ORANGE;
SET COLOR_DOT WHITE;
SET COLOR_ARC YELLOW;
SET COLOR_BODY GREEN;
SET COLOR_NOTE PURPLE;
SET PROP_DISPLAY VALUE;
SET PAGE_NUMBER P65;
FORCEADD OFFPAGE..1
(-1325 2750);
FORCEPROP 2 LAST $XR0 34 
J 0
(-1546 2750);
DISPLAY 0.638298 (-1546 2750);
PAINT MONO (-1546 2750);
FORCEPROP 2 LAST CDS_LIB standard
J 0
(-1325 2750);
PAINT MONO (-1325 2750);
DISPLAY INVISIBLE (-1325 2750);
FORCEPROP 1 LAST OFFPAGE TRUE
J 0
(-1000 2625);
DISPLAY 0.872340 (-1000 2625);
DISPLAY INVISIBLE (-1000 2625);
FORCEPROP 1 LAST COMMENT_BODY TRUE
J 0
(-1200 2650);
DISPLAY 0.872340 (-1200 2650);
PAINT GREEN (-1200 2650);
DISPLAY INVISIBLE (-1200 2650);
FORCEPROP 2 LAST PATH I1
J 0
(-1275 2825);
DISPLAY 1.021277 (-1275 2825);
DISPLAY INVISIBLE (-1275 2825);
FORCEADD TAP..1
R 2
(-75 1875);
FORCEPROP 3 LASTPIN (-25 1875) SIG_NAME UPI_CPU0_CPU1_P2P2_DN<6>
J 0
(-15 1885);
DISPLAY 0.659574 (-15 1885);
PAINT MONO (-15 1885);
DISPLAY INVISIBLE (-15 1885);
FORCEPROP 1 LASTPIN (-25 1875) BN 6
J 2
(-13 1883);
DISPLAY 0.680851 (-13 1883);
PAINT GREEN (-13 1883);
FORCEPROP 2 LAST CDS_LIB standard
J 0
(-75 1875);
DISPLAY INVISIBLE (-75 1875);
FORCEPROP 1 LAST BODY_TYPE PLUMBING
J 2
(-75 1925);
DISPLAY 0.872340 (-75 1925);
PAINT GREEN (-75 1925);
DISPLAY INVISIBLE (-75 1925);
FORCEPROP 1 LAST HDL_TAP TRUE
J 2
(-400 1750);
DISPLAY 0.872340 (-400 1750);
DISPLAY INVISIBLE (-400 1750);
FORCEPROP 1 LAST PATH I10
J 2
(-73 1875);
DISPLAY 0.872340 (-73 1875);
PAINT GREEN (-73 1875);
DISPLAY INVISIBLE (-73 1875);
FORCEADD OFFPAGE..2
(4500 2750);
FORCEPROP 2 LAST $XR0 34 
J 0
(4689 2750);
DISPLAY 0.638298 (4689 2750);
PAINT MONO (4689 2750);
FORCEPROP 2 LAST CDS_LIB standard
J 0
(4500 2750);
PAINT MONO (4500 2750);
DISPLAY INVISIBLE (4500 2750);
FORCEPROP 1 LAST OFFPAGE TRUE
J 0
(4825 2625);
DISPLAY 1.170213 (4825 2625);
PAINT GREEN (4825 2625);
DISPLAY INVISIBLE (4825 2625);
FORCEPROP 1 LAST COMMENT_BODY TRUE
J 0
(4455 2655);
DISPLAY 1.170213 (4455 2655);
PAINT GREEN (4455 2655);
DISPLAY INVISIBLE (4455 2655);
FORCEPROP 2 LAST PATH I100
J 0
(4675 2825);
DISPLAY 1.021277 (4675 2825);
DISPLAY INVISIBLE (4675 2825);
FORCEADD OFFPAGE..2
(4500 4000);
FORCEPROP 2 LAST $XR0 34 
J 0
(4689 4000);
DISPLAY 0.638298 (4689 4000);
PAINT MONO (4689 4000);
FORCEPROP 2 LAST CDS_LIB standard
J 0
(4500 4000);
PAINT MONO (4500 4000);
DISPLAY INVISIBLE (4500 4000);
FORCEPROP 1 LAST OFFPAGE TRUE
J 0
(4825 3875);
DISPLAY 1.170213 (4825 3875);
PAINT GREEN (4825 3875);
DISPLAY INVISIBLE (4825 3875);
FORCEPROP 1 LAST COMMENT_BODY TRUE
J 0
(4455 3905);
DISPLAY 1.170213 (4455 3905);
PAINT GREEN (4455 3905);
DISPLAY INVISIBLE (4455 3905);
FORCEPROP 2 LAST PATH I101
J 0
(4675 4075);
DISPLAY 1.021277 (4675 4075);
DISPLAY INVISIBLE (4675 4075);
FORCEADD TAP..1
R 2
(-75 1975);
FORCEPROP 3 LASTPIN (-25 1975) SIG_NAME UPI_CPU0_CPU1_P2P2_DN<8>
J 0
(-15 1985);
DISPLAY 0.659574 (-15 1985);
PAINT MONO (-15 1985);
DISPLAY INVISIBLE (-15 1985);
FORCEPROP 1 LASTPIN (-25 1975) BN 8
J 2
(-13 1983);
DISPLAY 0.680851 (-13 1983);
PAINT GREEN (-13 1983);
FORCEPROP 2 LAST CDS_LIB standard
J 0
(-75 1975);
DISPLAY INVISIBLE (-75 1975);
FORCEPROP 1 LAST BODY_TYPE PLUMBING
J 2
(-75 2025);
DISPLAY 0.872340 (-75 2025);
PAINT GREEN (-75 2025);
DISPLAY INVISIBLE (-75 2025);
FORCEPROP 1 LAST HDL_TAP TRUE
J 2
(-400 1850);
DISPLAY 0.872340 (-400 1850);
DISPLAY INVISIBLE (-400 1850);
FORCEPROP 1 LAST PATH I11
J 2
(-73 1975);
DISPLAY 0.872340 (-73 1975);
PAINT GREEN (-73 1975);
DISPLAY INVISIBLE (-73 1975);
FORCEADD TAP..1
R 2
(-75 2025);
FORCEPROP 3 LASTPIN (-25 2025) SIG_NAME UPI_CPU0_CPU1_P2P2_DN<9>
J 0
(-15 2035);
DISPLAY 0.659574 (-15 2035);
PAINT MONO (-15 2035);
DISPLAY INVISIBLE (-15 2035);
FORCEPROP 1 LASTPIN (-25 2025) BN 9
J 2
(-13 2033);
DISPLAY 0.680851 (-13 2033);
PAINT GREEN (-13 2033);
FORCEPROP 2 LAST CDS_LIB standard
J 0
(-75 2025);
DISPLAY INVISIBLE (-75 2025);
FORCEPROP 1 LAST BODY_TYPE PLUMBING
J 2
(-75 2075);
DISPLAY 0.872340 (-75 2075);
PAINT GREEN (-75 2075);
DISPLAY INVISIBLE (-75 2075);
FORCEPROP 1 LAST HDL_TAP TRUE
J 2
(-400 1900);
DISPLAY 0.872340 (-400 1900);
DISPLAY INVISIBLE (-400 1900);
FORCEPROP 1 LAST PATH I12
J 2
(-73 2025);
DISPLAY 0.872340 (-73 2025);
PAINT GREEN (-73 2025);
DISPLAY INVISIBLE (-73 2025);
FORCEADD TAP..1
R 2
(-75 2075);
FORCEPROP 3 LASTPIN (-25 2075) SIG_NAME UPI_CPU0_CPU1_P2P2_DN<10>
J 0
(-15 2085);
DISPLAY 0.659574 (-15 2085);
PAINT MONO (-15 2085);
DISPLAY INVISIBLE (-15 2085);
FORCEPROP 1 LASTPIN (-25 2075) BN 10
J 2
(-13 2083);
DISPLAY 0.680851 (-13 2083);
PAINT GREEN (-13 2083);
FORCEPROP 2 LAST CDS_LIB standard
J 0
(-75 2075);
DISPLAY INVISIBLE (-75 2075);
FORCEPROP 1 LAST BODY_TYPE PLUMBING
J 2
(-75 2125);
DISPLAY 0.872340 (-75 2125);
PAINT GREEN (-75 2125);
DISPLAY INVISIBLE (-75 2125);
FORCEPROP 1 LAST HDL_TAP TRUE
J 2
(-400 1950);
DISPLAY 0.872340 (-400 1950);
DISPLAY INVISIBLE (-400 1950);
FORCEPROP 1 LAST PATH I13
J 2
(-73 2075);
DISPLAY 0.872340 (-73 2075);
PAINT GREEN (-73 2075);
DISPLAY INVISIBLE (-73 2075);
FORCEADD TAP..1
R 2
(-75 2125);
FORCEPROP 3 LASTPIN (-25 2125) SIG_NAME UPI_CPU0_CPU1_P2P2_DN<11>
J 0
(-15 2135);
DISPLAY 0.659574 (-15 2135);
PAINT MONO (-15 2135);
DISPLAY INVISIBLE (-15 2135);
FORCEPROP 1 LASTPIN (-25 2125) BN 11
J 2
(-13 2133);
DISPLAY 0.680851 (-13 2133);
PAINT GREEN (-13 2133);
FORCEPROP 2 LAST CDS_LIB standard
J 0
(-75 2125);
DISPLAY INVISIBLE (-75 2125);
FORCEPROP 1 LAST BODY_TYPE PLUMBING
J 2
(-75 2175);
DISPLAY 0.872340 (-75 2175);
PAINT GREEN (-75 2175);
DISPLAY INVISIBLE (-75 2175);
FORCEPROP 1 LAST HDL_TAP TRUE
J 2
(-400 2000);
DISPLAY 0.872340 (-400 2000);
DISPLAY INVISIBLE (-400 2000);
FORCEPROP 1 LAST PATH I14
J 2
(-73 2125);
DISPLAY 0.872340 (-73 2125);
PAINT GREEN (-73 2125);
DISPLAY INVISIBLE (-73 2125);
FORCEADD TAP..1
R 2
(-75 2175);
FORCEPROP 3 LASTPIN (-25 2175) SIG_NAME UPI_CPU0_CPU1_P2P2_DN<12>
J 0
(-15 2185);
DISPLAY 0.659574 (-15 2185);
PAINT MONO (-15 2185);
DISPLAY INVISIBLE (-15 2185);
FORCEPROP 1 LASTPIN (-25 2175) BN 12
J 2
(-13 2183);
DISPLAY 0.680851 (-13 2183);
PAINT GREEN (-13 2183);
FORCEPROP 2 LAST CDS_LIB standard
J 0
(-75 2175);
DISPLAY INVISIBLE (-75 2175);
FORCEPROP 1 LAST BODY_TYPE PLUMBING
J 2
(-75 2225);
DISPLAY 0.872340 (-75 2225);
PAINT GREEN (-75 2225);
DISPLAY INVISIBLE (-75 2225);
FORCEPROP 1 LAST HDL_TAP TRUE
J 2
(-400 2050);
DISPLAY 0.872340 (-400 2050);
DISPLAY INVISIBLE (-400 2050);
FORCEPROP 1 LAST PATH I15
J 2
(-73 2175);
DISPLAY 0.872340 (-73 2175);
PAINT GREEN (-73 2175);
DISPLAY INVISIBLE (-73 2175);
FORCEADD SOCKET4677_AZIF0045P001C01CS..24
(1625 2775);
FORCEPROP 1 LAST PART_NUMBER DGA^7000023
J 0
(575 4225);
DISPLAY 0.723404 (575 4225);
PAINT GREEN (575 4225);
DISPLAY INVISIBLE (575 4225);
FORCEPROP 2 LAST VALUE SOCKET4677_AZIF0045-P001C01CS
J 0
(575 4350);
DISPLAY 1.021277 (575 4350);
FORCEPROP 1 LAST MATERIAL IO
J 0
(575 4150);
DISPLAY 0.723404 (575 4150);
PAINT GREEN (575 4150);
FORCEPROP 2 LAST PART_TYPE SMLF
J 0
(575 4400);
DISPLAY 1.021277 (575 4400);
FORCEPROP 1 LAST $LOCATION U1
J 0
(575 4300);
DISPLAY 0.723404 (575 4300);
PAINT GREEN (575 4300);
FORCEPROP 0 LASTPIN (425 1575) $PN E80
J 2
(415 1585);
DISPLAY 0.680851 (415 1585);
PAINT MONO (415 1585);
FORCEPROP 0 LASTPIN (425 1625) $PN F81
J 2
(415 1635);
DISPLAY 0.680851 (415 1635);
PAINT MONO (415 1635);
FORCEPROP 0 LASTPIN (425 1675) $PN G82
J 2
(415 1685);
DISPLAY 0.680851 (415 1685);
PAINT MONO (415 1685);
FORCEPROP 0 LASTPIN (425 1725) $PN K79
J 2
(415 1735);
DISPLAY 0.680851 (415 1735);
PAINT MONO (415 1735);
FORCEPROP 0 LASTPIN (425 1775) $PN J82
J 2
(415 1785);
DISPLAY 0.680851 (415 1785);
PAINT MONO (415 1785);
FORCEPROP 0 LASTPIN (425 1825) $PN L80
J 2
(415 1835);
DISPLAY 0.680851 (415 1835);
PAINT MONO (415 1835);
FORCEPROP 0 LASTPIN (425 1875) $PN AC80
J 2
(415 1885);
DISPLAY 0.680851 (415 1885);
PAINT MONO (415 1885);
FORCEPROP 0 LASTPIN (425 1925) $PN AD81
J 2
(415 1935);
DISPLAY 0.680851 (415 1935);
PAINT MONO (415 1935);
FORCEPROP 0 LASTPIN (425 1975) $PN AF79
J 2
(415 1985);
DISPLAY 0.680851 (415 1985);
PAINT MONO (415 1985);
FORCEPROP 0 LASTPIN (425 2025) $PN AE82
J 2
(415 2035);
DISPLAY 0.680851 (415 2035);
PAINT MONO (415 2035);
FORCEPROP 0 LASTPIN (425 2075) $PN AJ80
J 2
(415 2085);
DISPLAY 0.680851 (415 2085);
PAINT MONO (415 2085);
FORCEPROP 0 LASTPIN (425 2125) $PN AG82
J 2
(415 2135);
DISPLAY 0.680851 (415 2135);
PAINT MONO (415 2135);
FORCEPROP 0 LASTPIN (425 2175) $PN BA72
J 2
(415 2185);
DISPLAY 0.680851 (415 2185);
PAINT MONO (415 2185);
FORCEPROP 0 LASTPIN (425 2225) $PN AV73
J 2
(415 2235);
DISPLAY 0.680851 (415 2235);
PAINT MONO (415 2235);
FORCEPROP 0 LASTPIN (425 2275) $PN AY75
J 2
(415 2285);
DISPLAY 0.680851 (415 2285);
PAINT MONO (415 2285);
FORCEPROP 0 LASTPIN (425 2325) $PN BB75
J 2
(415 2335);
DISPLAY 0.680851 (415 2335);
PAINT MONO (415 2335);
FORCEPROP 0 LASTPIN (425 2375) $PN AW74
J 2
(415 2385);
DISPLAY 0.680851 (415 2385);
PAINT MONO (415 2385);
FORCEPROP 0 LASTPIN (425 2425) $PN BH75
J 2
(415 2435);
DISPLAY 0.680851 (415 2435);
PAINT MONO (415 2435);
FORCEPROP 0 LASTPIN (425 2475) $PN BJ76
J 2
(415 2485);
DISPLAY 0.680851 (415 2485);
PAINT MONO (415 2485);
FORCEPROP 0 LASTPIN (425 2525) $PN BL76
J 2
(415 2535);
DISPLAY 0.680851 (415 2535);
PAINT MONO (415 2535);
FORCEPROP 0 LASTPIN (425 2575) $PN BG74
J 2
(415 2585);
DISPLAY 0.680851 (415 2585);
PAINT MONO (415 2585);
FORCEPROP 0 LASTPIN (425 2625) $PN BN74
J 2
(415 2635);
DISPLAY 0.680851 (415 2635);
PAINT MONO (415 2635);
FORCEPROP 0 LASTPIN (425 2675) $PN BK73
J 2
(415 2685);
DISPLAY 0.680851 (415 2685);
PAINT MONO (415 2685);
FORCEPROP 0 LASTPIN (425 2725) $PN BD73
J 2
(415 2735);
DISPLAY 0.680851 (415 2735);
PAINT MONO (415 2735);
FORCEPROP 0 LASTPIN (425 2825) $PN G80
J 2
(415 2835);
DISPLAY 0.680851 (415 2835);
PAINT MONO (415 2835);
FORCEPROP 0 LASTPIN (425 2875) $PN E82
J 2
(415 2885);
DISPLAY 0.680851 (415 2885);
PAINT MONO (415 2885);
FORCEPROP 0 LASTPIN (425 2925) $PN H83
J 2
(415 2935);
DISPLAY 0.680851 (415 2935);
PAINT MONO (415 2935);
FORCEPROP 0 LASTPIN (425 2975) $PN M79
J 2
(415 2985);
DISPLAY 0.680851 (415 2985);
PAINT MONO (415 2985);
FORCEPROP 0 LASTPIN (425 3025) $PN L82
J 2
(415 3035);
DISPLAY 0.680851 (415 3035);
PAINT MONO (415 3035);
FORCEPROP 0 LASTPIN (425 3075) $PN K81
J 2
(415 3085);
DISPLAY 0.680851 (415 3085);
PAINT MONO (415 3085);
FORCEPROP 0 LASTPIN (425 3125) $PN AE80
J 2
(415 3135);
DISPLAY 0.680851 (415 3135);
PAINT MONO (415 3135);
FORCEPROP 0 LASTPIN (425 3175) $PN AC82
J 2
(415 3185);
DISPLAY 0.680851 (415 3185);
PAINT MONO (415 3185);
FORCEPROP 0 LASTPIN (425 3225) $PN AG80
J 2
(415 3235);
DISPLAY 0.680851 (415 3235);
PAINT MONO (415 3235);
FORCEPROP 0 LASTPIN (425 3275) $PN AF83
J 2
(415 3285);
DISPLAY 0.680851 (415 3285);
PAINT MONO (415 3285);
FORCEPROP 0 LASTPIN (425 3325) $PN AH81
J 2
(415 3335);
DISPLAY 0.680851 (415 3335);
PAINT MONO (415 3335);
FORCEPROP 0 LASTPIN (425 3375) $PN AJ82
J 2
(415 3385);
DISPLAY 0.680851 (415 3385);
PAINT MONO (415 3385);
FORCEPROP 0 LASTPIN (425 3425) $PN BB73
J 2
(415 3435);
DISPLAY 0.680851 (415 3435);
PAINT MONO (415 3435);
FORCEPROP 0 LASTPIN (425 3475) $PN AY73
J 2
(415 3485);
DISPLAY 0.680851 (415 3485);
PAINT MONO (415 3485);
FORCEPROP 0 LASTPIN (425 3525) $PN BA76
J 2
(415 3535);
DISPLAY 0.680851 (415 3535);
PAINT MONO (415 3535);
FORCEPROP 0 LASTPIN (425 3575) $PN BD75
J 2
(415 3585);
DISPLAY 0.680851 (415 3585);
PAINT MONO (415 3585);
FORCEPROP 0 LASTPIN (425 3625) $PN AV75
J 2
(415 3635);
DISPLAY 0.680851 (415 3635);
PAINT MONO (415 3635);
FORCEPROP 0 LASTPIN (425 3675) $PN BG76
J 2
(415 3685);
DISPLAY 0.680851 (415 3685);
PAINT MONO (415 3685);
FORCEPROP 0 LASTPIN (425 3725) $PN BK77
J 2
(415 3735);
DISPLAY 0.680851 (415 3735);
PAINT MONO (415 3735);
FORCEPROP 0 LASTPIN (425 3775) $PN BN76
J 2
(415 3785);
DISPLAY 0.680851 (415 3785);
PAINT MONO (415 3785);
FORCEPROP 0 LASTPIN (425 3825) $PN BJ74
J 2
(415 3835);
DISPLAY 0.680851 (415 3835);
PAINT MONO (415 3835);
FORCEPROP 0 LASTPIN (425 3875) $PN BM75
J 2
(415 3885);
DISPLAY 0.680851 (415 3885);
PAINT MONO (415 3885);
FORCEPROP 0 LASTPIN (425 3925) $PN BL74
J 2
(415 3935);
DISPLAY 0.680851 (415 3935);
PAINT MONO (415 3935);
FORCEPROP 0 LASTPIN (425 3975) $PN BC74
J 2
(415 3985);
DISPLAY 0.680851 (415 3985);
PAINT MONO (415 3985);
FORCEPROP 0 LASTPIN (2825 1575) $PN B85
J 0
(2835 1585);
DISPLAY 0.680851 (2835 1585);
PAINT MONO (2835 1585);
FORCEPROP 0 LASTPIN (2825 1625) $PN E84
J 0
(2835 1635);
DISPLAY 0.680851 (2835 1635);
PAINT MONO (2835 1635);
FORCEPROP 0 LASTPIN (2825 1675) $PN D87
J 0
(2835 1685);
DISPLAY 0.680851 (2835 1685);
PAINT MONO (2835 1685);
FORCEPROP 0 LASTPIN (2825 1725) $PN F87
J 0
(2835 1735);
DISPLAY 0.680851 (2835 1735);
PAINT MONO (2835 1735);
FORCEPROP 0 LASTPIN (2825 1775) $PN H85
J 0
(2835 1785);
DISPLAY 0.680851 (2835 1785);
PAINT MONO (2835 1785);
FORCEPROP 0 LASTPIN (2825 1825) $PN P81
J 0
(2835 1835);
DISPLAY 0.680851 (2835 1835);
PAINT MONO (2835 1835);
FORCEPROP 0 LASTPIN (2825 1875) $PN R82
J 0
(2835 1885);
DISPLAY 0.680851 (2835 1885);
PAINT MONO (2835 1885);
FORCEPROP 0 LASTPIN (2825 1925) $PN U80
J 0
(2835 1935);
DISPLAY 0.680851 (2835 1935);
PAINT MONO (2835 1935);
FORCEPROP 0 LASTPIN (2825 1975) $PN V83
J 0
(2835 1985);
DISPLAY 0.680851 (2835 1985);
PAINT MONO (2835 1985);
FORCEPROP 0 LASTPIN (2825 2025) $PN Y81
J 0
(2835 2035);
DISPLAY 0.680851 (2835 2035);
PAINT MONO (2835 2035);
FORCEPROP 0 LASTPIN (2825 2075) $PN AW78
J 0
(2835 2085);
DISPLAY 0.680851 (2835 2085);
PAINT MONO (2835 2085);
FORCEPROP 0 LASTPIN (2825 2125) $PN AU78
J 0
(2835 2135);
DISPLAY 0.680851 (2835 2135);
PAINT MONO (2835 2135);
FORCEPROP 0 LASTPIN (2825 2175) $PN AM81
J 0
(2835 2185);
DISPLAY 0.680851 (2835 2185);
PAINT MONO (2835 2185);
FORCEPROP 0 LASTPIN (2825 2225) $PN AN82
J 0
(2835 2235);
DISPLAY 0.680851 (2835 2235);
PAINT MONO (2835 2235);
FORCEPROP 0 LASTPIN (2825 2275) $PN AR80
J 0
(2835 2285);
DISPLAY 0.680851 (2835 2285);
PAINT MONO (2835 2285);
FORCEPROP 0 LASTPIN (2825 2325) $PN AT83
J 0
(2835 2335);
DISPLAY 0.680851 (2835 2335);
PAINT MONO (2835 2335);
FORCEPROP 0 LASTPIN (2825 2375) $PN AV81
J 0
(2835 2385);
DISPLAY 0.680851 (2835 2385);
PAINT MONO (2835 2385);
FORCEPROP 0 LASTPIN (2825 2425) $PN BA80
J 0
(2835 2435);
DISPLAY 0.680851 (2835 2435);
PAINT MONO (2835 2435);
FORCEPROP 0 LASTPIN (2825 2475) $PN BC82
J 0
(2835 2485);
DISPLAY 0.680851 (2835 2485);
PAINT MONO (2835 2485);
FORCEPROP 0 LASTPIN (2825 2525) $PN BE82
J 0
(2835 2535);
DISPLAY 0.680851 (2835 2535);
PAINT MONO (2835 2535);
FORCEPROP 0 LASTPIN (2825 2575) $PN BD79
J 0
(2835 2585);
DISPLAY 0.680851 (2835 2585);
PAINT MONO (2835 2585);
FORCEPROP 0 LASTPIN (2825 2625) $PN BF81
J 0
(2835 2635);
DISPLAY 0.680851 (2835 2635);
PAINT MONO (2835 2635);
FORCEPROP 0 LASTPIN (2825 2675) $PN BG80
J 0
(2835 2685);
DISPLAY 0.680851 (2835 2685);
PAINT MONO (2835 2685);
FORCEPROP 0 LASTPIN (2825 2725) $PN BM71
J 0
(2835 2735);
DISPLAY 0.680851 (2835 2735);
PAINT MONO (2835 2735);
FORCEPROP 0 LASTPIN (2825 2825) $PN D85
J 0
(2835 2835);
DISPLAY 0.680851 (2835 2835);
PAINT MONO (2835 2835);
FORCEPROP 0 LASTPIN (2825 2875) $PN F85
J 0
(2835 2885);
DISPLAY 0.680851 (2835 2885);
PAINT MONO (2835 2885);
FORCEPROP 0 LASTPIN (2825 2925) $PN E88
J 0
(2835 2935);
DISPLAY 0.680851 (2835 2935);
PAINT MONO (2835 2935);
FORCEPROP 0 LASTPIN (2825 2975) $PN H87
J 0
(2835 2985);
DISPLAY 0.680851 (2835 2985);
PAINT MONO (2835 2985);
FORCEPROP 0 LASTPIN (2825 3025) $PN G86
J 0
(2835 3035);
DISPLAY 0.680851 (2835 3035);
PAINT MONO (2835 3035);
FORCEPROP 0 LASTPIN (2825 3075) $PN T81
J 0
(2835 3085);
DISPLAY 0.680851 (2835 3085);
PAINT MONO (2835 3085);
FORCEPROP 0 LASTPIN (2825 3125) $PN P83
J 0
(2835 3135);
DISPLAY 0.680851 (2835 3135);
PAINT MONO (2835 3135);
FORCEPROP 0 LASTPIN (2825 3175) $PN V81
J 0
(2835 3185);
DISPLAY 0.680851 (2835 3185);
PAINT MONO (2835 3185);
FORCEPROP 0 LASTPIN (2825 3225) $PN Y83
J 0
(2835 3235);
DISPLAY 0.680851 (2835 3235);
PAINT MONO (2835 3235);
FORCEPROP 0 LASTPIN (2825 3275) $PN W82
J 0
(2835 3285);
DISPLAY 0.680851 (2835 3285);
PAINT MONO (2835 3285);
FORCEPROP 0 LASTPIN (2825 3325) $PN BA78
J 0
(2835 3335);
DISPLAY 0.680851 (2835 3335);
PAINT MONO (2835 3335);
FORCEPROP 0 LASTPIN (2825 3375) $PN AV79
J 0
(2835 3385);
DISPLAY 0.680851 (2835 3385);
PAINT MONO (2835 3385);
FORCEPROP 0 LASTPIN (2825 3425) $PN AP81
J 0
(2835 3435);
DISPLAY 0.680851 (2835 3435);
PAINT MONO (2835 3435);
FORCEPROP 0 LASTPIN (2825 3475) $PN AM83
J 0
(2835 3485);
DISPLAY 0.680851 (2835 3485);
PAINT MONO (2835 3485);
FORCEPROP 0 LASTPIN (2825 3525) $PN AT81
J 0
(2835 3535);
DISPLAY 0.680851 (2835 3535);
PAINT MONO (2835 3535);
FORCEPROP 0 LASTPIN (2825 3575) $PN AV83
J 0
(2835 3585);
DISPLAY 0.680851 (2835 3585);
PAINT MONO (2835 3585);
FORCEPROP 0 LASTPIN (2825 3625) $PN AU82
J 0
(2835 3635);
DISPLAY 0.680851 (2835 3635);
PAINT MONO (2835 3635);
FORCEPROP 0 LASTPIN (2825 3675) $PN BB81
J 0
(2835 3685);
DISPLAY 0.680851 (2835 3685);
PAINT MONO (2835 3685);
FORCEPROP 0 LASTPIN (2825 3725) $PN BA82
J 0
(2835 3735);
DISPLAY 0.680851 (2835 3735);
PAINT MONO (2835 3735);
FORCEPROP 0 LASTPIN (2825 3775) $PN BD83
J 0
(2835 3785);
DISPLAY 0.680851 (2835 3785);
PAINT MONO (2835 3785);
FORCEPROP 0 LASTPIN (2825 3825) $PN BC80
J 0
(2835 3835);
DISPLAY 0.680851 (2835 3835);
PAINT MONO (2835 3835);
FORCEPROP 0 LASTPIN (2825 3875) $PN BG82
J 0
(2835 3885);
DISPLAY 0.680851 (2835 3885);
PAINT MONO (2835 3885);
FORCEPROP 0 LASTPIN (2825 3925) $PN BE80
J 0
(2835 3935);
DISPLAY 0.680851 (2835 3935);
PAINT MONO (2835 3935);
FORCEPROP 0 LASTPIN (2825 3975) $PN BN72
J 0
(2835 3985);
DISPLAY 0.680851 (2835 3985);
PAINT MONO (2835 3985);
FORCEPROP 1 LAST CDS_LMAN_SYM_OUTLINE -1050,1350,1050,-1350
J 0
(1625 2775);
DISPLAY 0.468085 (1625 2775);
PAINT GREEN (1625 2775);
DISPLAY INVISIBLE (1625 2775);
FORCEPROP 1 LAST NEEDS_NO_SIZE TRUE
J 0
(1625 2775);
DISPLAY 0.723404 (1625 2775);
PAINT GREEN (1625 2775);
DISPLAY INVISIBLE (1625 2775);
FORCEPROP 2 LAST CDS_LIB pure_quanta
J 0
(1625 2775);
DISPLAY INVISIBLE (1625 2775);
FORCEPROP 0 LAST CDS_LOCATION U1
J 0
(575 4450);
DISPLAY 1.021277 (575 4450);
DISPLAY INVISIBLE (575 4450);
FORCEPROP 0 LAST $SEC 24
J 0
(575 4450);
DISPLAY 0.680851 (575 4450);
PAINT MONO (575 4450);
DISPLAY INVISIBLE (575 4450);
FORCEPROP 2 LAST CDS_SEC 24
J 0
(575 4450);
DISPLAY 1.021277 (575 4450);
DISPLAY INVISIBLE (575 4450);
FORCEPROP 1 LAST PATH I16
J 0
(1625 2775);
DISPLAY 0.723404 (1625 2775);
PAINT GREEN (1625 2775);
DISPLAY INVISIBLE (1625 2775);
FORCEADD TAP..1
R 2
(-75 2225);
FORCEPROP 3 LASTPIN (-25 2225) SIG_NAME UPI_CPU0_CPU1_P2P2_DN<13>
J 0
(-15 2235);
DISPLAY 0.659574 (-15 2235);
PAINT MONO (-15 2235);
DISPLAY INVISIBLE (-15 2235);
FORCEPROP 1 LASTPIN (-25 2225) BN 13
J 2
(-13 2233);
DISPLAY 0.680851 (-13 2233);
PAINT GREEN (-13 2233);
FORCEPROP 2 LAST CDS_LIB standard
J 0
(-75 2225);
DISPLAY INVISIBLE (-75 2225);
FORCEPROP 1 LAST BODY_TYPE PLUMBING
J 2
(-75 2275);
DISPLAY 0.872340 (-75 2275);
PAINT GREEN (-75 2275);
DISPLAY INVISIBLE (-75 2275);
FORCEPROP 1 LAST HDL_TAP TRUE
J 2
(-400 2100);
DISPLAY 0.872340 (-400 2100);
DISPLAY INVISIBLE (-400 2100);
FORCEPROP 1 LAST PATH I17
J 2
(-73 2225);
DISPLAY 0.872340 (-73 2225);
PAINT GREEN (-73 2225);
DISPLAY INVISIBLE (-73 2225);
FORCEADD TAP..1
R 2
(-75 2275);
FORCEPROP 3 LASTPIN (-25 2275) SIG_NAME UPI_CPU0_CPU1_P2P2_DN<14>
J 0
(-15 2285);
DISPLAY 0.659574 (-15 2285);
PAINT MONO (-15 2285);
DISPLAY INVISIBLE (-15 2285);
FORCEPROP 1 LASTPIN (-25 2275) BN 14
J 2
(-13 2283);
DISPLAY 0.680851 (-13 2283);
PAINT GREEN (-13 2283);
FORCEPROP 2 LAST CDS_LIB standard
J 0
(-75 2275);
DISPLAY INVISIBLE (-75 2275);
FORCEPROP 1 LAST BODY_TYPE PLUMBING
J 2
(-75 2325);
DISPLAY 0.872340 (-75 2325);
PAINT GREEN (-75 2325);
DISPLAY INVISIBLE (-75 2325);
FORCEPROP 1 LAST HDL_TAP TRUE
J 2
(-400 2150);
DISPLAY 0.872340 (-400 2150);
DISPLAY INVISIBLE (-400 2150);
FORCEPROP 1 LAST PATH I18
J 2
(-73 2275);
DISPLAY 0.872340 (-73 2275);
PAINT GREEN (-73 2275);
DISPLAY INVISIBLE (-73 2275);
FORCEADD TAP..1
R 2
(-75 2325);
FORCEPROP 3 LASTPIN (-25 2325) SIG_NAME UPI_CPU0_CPU1_P2P2_DN<15>
J 0
(-15 2335);
DISPLAY 0.659574 (-15 2335);
PAINT MONO (-15 2335);
DISPLAY INVISIBLE (-15 2335);
FORCEPROP 1 LASTPIN (-25 2325) BN 15
J 2
(-13 2333);
DISPLAY 0.680851 (-13 2333);
PAINT GREEN (-13 2333);
FORCEPROP 2 LAST CDS_LIB standard
J 0
(-75 2325);
DISPLAY INVISIBLE (-75 2325);
FORCEPROP 1 LAST BODY_TYPE PLUMBING
J 2
(-75 2375);
DISPLAY 0.872340 (-75 2375);
PAINT GREEN (-75 2375);
DISPLAY INVISIBLE (-75 2375);
FORCEPROP 1 LAST HDL_TAP TRUE
J 2
(-400 2200);
DISPLAY 0.872340 (-400 2200);
DISPLAY INVISIBLE (-400 2200);
FORCEPROP 1 LAST PATH I19
J 2
(-73 2325);
DISPLAY 0.872340 (-73 2325);
PAINT GREEN (-73 2325);
DISPLAY INVISIBLE (-73 2325);
FORCEADD OFFPAGE..1
(-1325 4000);
FORCEPROP 2 LAST $XR0 34 
J 0
(-1546 4000);
DISPLAY 0.638298 (-1546 4000);
PAINT MONO (-1546 4000);
FORCEPROP 2 LAST CDS_LIB standard
J 0
(-1325 4000);
PAINT MONO (-1325 4000);
DISPLAY INVISIBLE (-1325 4000);
FORCEPROP 1 LAST OFFPAGE TRUE
J 0
(-1000 3875);
DISPLAY 0.872340 (-1000 3875);
DISPLAY INVISIBLE (-1000 3875);
FORCEPROP 1 LAST COMMENT_BODY TRUE
J 0
(-1200 3900);
DISPLAY 0.872340 (-1200 3900);
PAINT GREEN (-1200 3900);
DISPLAY INVISIBLE (-1200 3900);
FORCEPROP 2 LAST PATH I2
J 0
(-1275 4075);
DISPLAY 1.021277 (-1275 4075);
DISPLAY INVISIBLE (-1275 4075);
FORCEADD TAP..1
R 2
(-75 2375);
FORCEPROP 3 LASTPIN (-25 2375) SIG_NAME UPI_CPU0_CPU1_P2P2_DN<16>
J 0
(-15 2385);
DISPLAY 0.659574 (-15 2385);
PAINT MONO (-15 2385);
DISPLAY INVISIBLE (-15 2385);
FORCEPROP 1 LASTPIN (-25 2375) BN 16
J 2
(-13 2383);
DISPLAY 0.680851 (-13 2383);
PAINT GREEN (-13 2383);
FORCEPROP 2 LAST CDS_LIB standard
J 0
(-75 2375);
PAINT MONO (-75 2375);
DISPLAY INVISIBLE (-75 2375);
FORCEPROP 1 LAST BODY_TYPE PLUMBING
J 2
(-75 2425);
DISPLAY 0.872340 (-75 2425);
PAINT GREEN (-75 2425);
DISPLAY INVISIBLE (-75 2425);
FORCEPROP 1 LAST HDL_TAP TRUE
J 2
(-400 2250);
DISPLAY 0.872340 (-400 2250);
DISPLAY INVISIBLE (-400 2250);
FORCEPROP 1 LAST PATH I20
J 2
(-73 2375);
DISPLAY 0.872340 (-73 2375);
PAINT GREEN (-73 2375);
DISPLAY INVISIBLE (-73 2375);
FORCEADD TAP..1
R 2
(-75 2425);
FORCEPROP 3 LASTPIN (-25 2425) SIG_NAME UPI_CPU0_CPU1_P2P2_DN<17>
J 0
(-15 2435);
DISPLAY 0.659574 (-15 2435);
PAINT MONO (-15 2435);
DISPLAY INVISIBLE (-15 2435);
FORCEPROP 1 LASTPIN (-25 2425) BN 17
J 2
(-13 2433);
DISPLAY 0.680851 (-13 2433);
PAINT GREEN (-13 2433);
FORCEPROP 2 LAST CDS_LIB standard
J 0
(-75 2425);
PAINT MONO (-75 2425);
DISPLAY INVISIBLE (-75 2425);
FORCEPROP 1 LAST BODY_TYPE PLUMBING
J 2
(-75 2475);
DISPLAY 0.872340 (-75 2475);
PAINT GREEN (-75 2475);
DISPLAY INVISIBLE (-75 2475);
FORCEPROP 1 LAST HDL_TAP TRUE
J 2
(-400 2300);
DISPLAY 0.872340 (-400 2300);
DISPLAY INVISIBLE (-400 2300);
FORCEPROP 1 LAST PATH I21
J 2
(-73 2425);
DISPLAY 0.872340 (-73 2425);
PAINT GREEN (-73 2425);
DISPLAY INVISIBLE (-73 2425);
FORCEADD TAP..1
R 2
(-75 2475);
FORCEPROP 3 LASTPIN (-25 2475) SIG_NAME UPI_CPU0_CPU1_P2P2_DN<18>
J 0
(-15 2485);
DISPLAY 0.659574 (-15 2485);
PAINT MONO (-15 2485);
DISPLAY INVISIBLE (-15 2485);
FORCEPROP 1 LASTPIN (-25 2475) BN 18
J 2
(-13 2483);
DISPLAY 0.680851 (-13 2483);
PAINT GREEN (-13 2483);
FORCEPROP 2 LAST CDS_LIB standard
J 0
(-75 2475);
PAINT MONO (-75 2475);
DISPLAY INVISIBLE (-75 2475);
FORCEPROP 1 LAST BODY_TYPE PLUMBING
J 2
(-75 2525);
DISPLAY 0.872340 (-75 2525);
PAINT GREEN (-75 2525);
DISPLAY INVISIBLE (-75 2525);
FORCEPROP 1 LAST HDL_TAP TRUE
J 2
(-400 2350);
DISPLAY 0.872340 (-400 2350);
DISPLAY INVISIBLE (-400 2350);
FORCEPROP 1 LAST PATH I22
J 2
(-73 2475);
DISPLAY 0.872340 (-73 2475);
PAINT GREEN (-73 2475);
DISPLAY INVISIBLE (-73 2475);
FORCEADD TAP..1
R 2
(-75 2525);
FORCEPROP 3 LASTPIN (-25 2525) SIG_NAME UPI_CPU0_CPU1_P2P2_DN<19>
J 0
(-15 2535);
DISPLAY 0.659574 (-15 2535);
PAINT MONO (-15 2535);
DISPLAY INVISIBLE (-15 2535);
FORCEPROP 1 LASTPIN (-25 2525) BN 19
J 2
(-13 2533);
DISPLAY 0.680851 (-13 2533);
PAINT GREEN (-13 2533);
FORCEPROP 2 LAST CDS_LIB standard
J 0
(-75 2525);
PAINT MONO (-75 2525);
DISPLAY INVISIBLE (-75 2525);
FORCEPROP 1 LAST BODY_TYPE PLUMBING
J 2
(-75 2575);
DISPLAY 0.872340 (-75 2575);
PAINT GREEN (-75 2575);
DISPLAY INVISIBLE (-75 2575);
FORCEPROP 1 LAST HDL_TAP TRUE
J 2
(-400 2400);
DISPLAY 0.872340 (-400 2400);
DISPLAY INVISIBLE (-400 2400);
FORCEPROP 1 LAST PATH I23
J 2
(-73 2525);
DISPLAY 0.872340 (-73 2525);
PAINT GREEN (-73 2525);
DISPLAY INVISIBLE (-73 2525);
FORCEADD TAP..1
R 2
(-75 2575);
FORCEPROP 3 LASTPIN (-25 2575) SIG_NAME UPI_CPU0_CPU1_P2P2_DN<20>
J 0
(-15 2585);
DISPLAY 0.659574 (-15 2585);
PAINT MONO (-15 2585);
DISPLAY INVISIBLE (-15 2585);
FORCEPROP 1 LASTPIN (-25 2575) BN 20
J 2
(-13 2583);
DISPLAY 0.680851 (-13 2583);
PAINT GREEN (-13 2583);
FORCEPROP 2 LAST CDS_LIB standard
J 0
(-75 2575);
PAINT MONO (-75 2575);
DISPLAY INVISIBLE (-75 2575);
FORCEPROP 1 LAST BODY_TYPE PLUMBING
J 2
(-75 2625);
DISPLAY 0.872340 (-75 2625);
PAINT GREEN (-75 2625);
DISPLAY INVISIBLE (-75 2625);
FORCEPROP 1 LAST HDL_TAP TRUE
J 2
(-400 2450);
DISPLAY 0.872340 (-400 2450);
DISPLAY INVISIBLE (-400 2450);
FORCEPROP 1 LAST PATH I24
J 2
(-73 2575);
DISPLAY 0.872340 (-73 2575);
PAINT GREEN (-73 2575);
DISPLAY INVISIBLE (-73 2575);
FORCEADD TAP..1
R 2
(-75 2675);
FORCEPROP 3 LASTPIN (-25 2675) SIG_NAME UPI_CPU0_CPU1_P2P2_DN<22>
J 0
(-15 2685);
DISPLAY 0.659574 (-15 2685);
PAINT MONO (-15 2685);
DISPLAY INVISIBLE (-15 2685);
FORCEPROP 1 LASTPIN (-25 2675) BN 22
J 2
(-13 2683);
DISPLAY 0.680851 (-13 2683);
PAINT GREEN (-13 2683);
FORCEPROP 2 LAST CDS_LIB standard
J 0
(-75 2675);
PAINT MONO (-75 2675);
DISPLAY INVISIBLE (-75 2675);
FORCEPROP 1 LAST BODY_TYPE PLUMBING
J 2
(-75 2725);
DISPLAY 0.872340 (-75 2725);
PAINT GREEN (-75 2725);
DISPLAY INVISIBLE (-75 2725);
FORCEPROP 1 LAST HDL_TAP TRUE
J 2
(-400 2550);
DISPLAY 0.872340 (-400 2550);
DISPLAY INVISIBLE (-400 2550);
FORCEPROP 1 LAST PATH I25
J 2
(-73 2675);
DISPLAY 0.872340 (-73 2675);
PAINT GREEN (-73 2675);
DISPLAY INVISIBLE (-73 2675);
FORCEADD TAP..1
R 2
(-75 2625);
FORCEPROP 3 LASTPIN (-25 2625) SIG_NAME UPI_CPU0_CPU1_P2P2_DN<21>
J 0
(-15 2635);
DISPLAY 0.659574 (-15 2635);
PAINT MONO (-15 2635);
DISPLAY INVISIBLE (-15 2635);
FORCEPROP 1 LASTPIN (-25 2625) BN 21
J 2
(-13 2633);
DISPLAY 0.680851 (-13 2633);
PAINT GREEN (-13 2633);
FORCEPROP 2 LAST CDS_LIB standard
J 0
(-75 2625);
PAINT MONO (-75 2625);
DISPLAY INVISIBLE (-75 2625);
FORCEPROP 1 LAST BODY_TYPE PLUMBING
J 2
(-75 2675);
DISPLAY 0.872340 (-75 2675);
PAINT GREEN (-75 2675);
DISPLAY INVISIBLE (-75 2675);
FORCEPROP 1 LAST HDL_TAP TRUE
J 2
(-400 2500);
DISPLAY 0.872340 (-400 2500);
DISPLAY INVISIBLE (-400 2500);
FORCEPROP 1 LAST PATH I26
J 2
(-73 2625);
DISPLAY 0.872340 (-73 2625);
PAINT GREEN (-73 2625);
DISPLAY INVISIBLE (-73 2625);
FORCEADD TAP..1
R 2
(-75 2725);
FORCEPROP 3 LASTPIN (-25 2725) SIG_NAME UPI_CPU0_CPU1_P2P2_DN<23>
J 0
(-15 2735);
DISPLAY 0.659574 (-15 2735);
PAINT MONO (-15 2735);
DISPLAY INVISIBLE (-15 2735);
FORCEPROP 1 LASTPIN (-25 2725) BN 23
J 2
(-13 2733);
DISPLAY 0.680851 (-13 2733);
PAINT GREEN (-13 2733);
FORCEPROP 2 LAST CDS_LIB standard
J 0
(-75 2725);
PAINT MONO (-75 2725);
DISPLAY INVISIBLE (-75 2725);
FORCEPROP 1 LAST BODY_TYPE PLUMBING
J 2
(-75 2775);
DISPLAY 0.872340 (-75 2775);
PAINT GREEN (-75 2775);
DISPLAY INVISIBLE (-75 2775);
FORCEPROP 1 LAST HDL_TAP TRUE
J 2
(-400 2600);
DISPLAY 0.872340 (-400 2600);
DISPLAY INVISIBLE (-400 2600);
FORCEPROP 1 LAST PATH I27
J 2
(-73 2725);
DISPLAY 0.872340 (-73 2725);
PAINT GREEN (-73 2725);
DISPLAY INVISIBLE (-73 2725);
FORCEADD TAP..1
R 2
(-75 2825);
FORCEPROP 3 LASTPIN (-25 2825) SIG_NAME UPI_CPU0_CPU1_P2P2_DP<0>
J 0
(-15 2835);
DISPLAY 0.659574 (-15 2835);
PAINT MONO (-15 2835);
DISPLAY INVISIBLE (-15 2835);
FORCEPROP 1 LASTPIN (-25 2825) BN 0
J 2
(-13 2833);
DISPLAY 0.680851 (-13 2833);
PAINT GREEN (-13 2833);
FORCEPROP 2 LAST CDS_LIB standard
J 0
(-75 2825);
DISPLAY INVISIBLE (-75 2825);
FORCEPROP 1 LAST BODY_TYPE PLUMBING
J 2
(-75 2875);
DISPLAY 0.872340 (-75 2875);
PAINT GREEN (-75 2875);
DISPLAY INVISIBLE (-75 2875);
FORCEPROP 1 LAST HDL_TAP TRUE
J 2
(-400 2700);
DISPLAY 0.872340 (-400 2700);
DISPLAY INVISIBLE (-400 2700);
FORCEPROP 1 LAST PATH I28
J 2
(-73 2825);
DISPLAY 0.872340 (-73 2825);
PAINT GREEN (-73 2825);
DISPLAY INVISIBLE (-73 2825);
FORCEADD TAP..1
R 2
(-75 2875);
FORCEPROP 3 LASTPIN (-25 2875) SIG_NAME UPI_CPU0_CPU1_P2P2_DP<1>
J 0
(-15 2885);
DISPLAY 0.659574 (-15 2885);
PAINT MONO (-15 2885);
DISPLAY INVISIBLE (-15 2885);
FORCEPROP 1 LASTPIN (-25 2875) BN 1
J 2
(-13 2883);
DISPLAY 0.680851 (-13 2883);
PAINT GREEN (-13 2883);
FORCEPROP 2 LAST CDS_LIB standard
J 0
(-75 2875);
DISPLAY INVISIBLE (-75 2875);
FORCEPROP 1 LAST BODY_TYPE PLUMBING
J 2
(-75 2925);
DISPLAY 0.872340 (-75 2925);
PAINT GREEN (-75 2925);
DISPLAY INVISIBLE (-75 2925);
FORCEPROP 1 LAST HDL_TAP TRUE
J 2
(-400 2750);
DISPLAY 0.872340 (-400 2750);
DISPLAY INVISIBLE (-400 2750);
FORCEPROP 1 LAST PATH I29
J 2
(-73 2875);
DISPLAY 0.872340 (-73 2875);
PAINT GREEN (-73 2875);
DISPLAY INVISIBLE (-73 2875);
FORCEADD TAP..1
R 2
(-75 1575);
FORCEPROP 3 LASTPIN (-25 1575) SIG_NAME UPI_CPU0_CPU1_P2P2_DN<0>
J 0
(-15 1585);
DISPLAY 0.659574 (-15 1585);
PAINT MONO (-15 1585);
DISPLAY INVISIBLE (-15 1585);
FORCEPROP 1 LASTPIN (-25 1575) BN 0
J 2
(-13 1583);
DISPLAY 0.680851 (-13 1583);
PAINT GREEN (-13 1583);
FORCEPROP 2 LAST CDS_LIB standard
J 0
(-75 1575);
DISPLAY INVISIBLE (-75 1575);
FORCEPROP 1 LAST BODY_TYPE PLUMBING
J 2
(-75 1625);
DISPLAY 0.872340 (-75 1625);
PAINT GREEN (-75 1625);
DISPLAY INVISIBLE (-75 1625);
FORCEPROP 1 LAST HDL_TAP TRUE
J 2
(-400 1450);
DISPLAY 0.872340 (-400 1450);
DISPLAY INVISIBLE (-400 1450);
FORCEPROP 1 LAST PATH I3
J 2
(-73 1575);
DISPLAY 0.872340 (-73 1575);
PAINT GREEN (-73 1575);
DISPLAY INVISIBLE (-73 1575);
FORCEADD TAP..1
R 2
(-75 2925);
FORCEPROP 3 LASTPIN (-25 2925) SIG_NAME UPI_CPU0_CPU1_P2P2_DP<2>
J 0
(-15 2935);
DISPLAY 0.659574 (-15 2935);
PAINT MONO (-15 2935);
DISPLAY INVISIBLE (-15 2935);
FORCEPROP 1 LASTPIN (-25 2925) BN 2
J 2
(-13 2933);
DISPLAY 0.680851 (-13 2933);
PAINT GREEN (-13 2933);
FORCEPROP 2 LAST CDS_LIB standard
J 0
(-75 2925);
DISPLAY INVISIBLE (-75 2925);
FORCEPROP 1 LAST BODY_TYPE PLUMBING
J 2
(-75 2975);
DISPLAY 0.872340 (-75 2975);
PAINT GREEN (-75 2975);
DISPLAY INVISIBLE (-75 2975);
FORCEPROP 1 LAST HDL_TAP TRUE
J 2
(-400 2800);
DISPLAY 0.872340 (-400 2800);
DISPLAY INVISIBLE (-400 2800);
FORCEPROP 1 LAST PATH I30
J 2
(-73 2925);
DISPLAY 0.872340 (-73 2925);
PAINT GREEN (-73 2925);
DISPLAY INVISIBLE (-73 2925);
FORCEADD TAP..1
R 2
(-75 2975);
FORCEPROP 3 LASTPIN (-25 2975) SIG_NAME UPI_CPU0_CPU1_P2P2_DP<3>
J 0
(-15 2985);
DISPLAY 0.659574 (-15 2985);
PAINT MONO (-15 2985);
DISPLAY INVISIBLE (-15 2985);
FORCEPROP 1 LASTPIN (-25 2975) BN 3
J 2
(-13 2983);
DISPLAY 0.680851 (-13 2983);
PAINT GREEN (-13 2983);
FORCEPROP 2 LAST CDS_LIB standard
J 0
(-75 2975);
DISPLAY INVISIBLE (-75 2975);
FORCEPROP 1 LAST BODY_TYPE PLUMBING
J 2
(-75 3025);
DISPLAY 0.872340 (-75 3025);
PAINT GREEN (-75 3025);
DISPLAY INVISIBLE (-75 3025);
FORCEPROP 1 LAST HDL_TAP TRUE
J 2
(-400 2850);
DISPLAY 0.872340 (-400 2850);
DISPLAY INVISIBLE (-400 2850);
FORCEPROP 1 LAST PATH I31
J 2
(-73 2975);
DISPLAY 0.872340 (-73 2975);
PAINT GREEN (-73 2975);
DISPLAY INVISIBLE (-73 2975);
FORCEADD TAP..1
R 2
(-75 3025);
FORCEPROP 3 LASTPIN (-25 3025) SIG_NAME UPI_CPU0_CPU1_P2P2_DP<4>
J 0
(-15 3035);
DISPLAY 0.659574 (-15 3035);
PAINT MONO (-15 3035);
DISPLAY INVISIBLE (-15 3035);
FORCEPROP 1 LASTPIN (-25 3025) BN 4
J 2
(-13 3033);
DISPLAY 0.680851 (-13 3033);
PAINT GREEN (-13 3033);
FORCEPROP 2 LAST CDS_LIB standard
J 0
(-75 3025);
DISPLAY INVISIBLE (-75 3025);
FORCEPROP 1 LAST BODY_TYPE PLUMBING
J 2
(-75 3075);
DISPLAY 0.872340 (-75 3075);
PAINT GREEN (-75 3075);
DISPLAY INVISIBLE (-75 3075);
FORCEPROP 1 LAST HDL_TAP TRUE
J 2
(-400 2900);
DISPLAY 0.872340 (-400 2900);
DISPLAY INVISIBLE (-400 2900);
FORCEPROP 1 LAST PATH I32
J 2
(-73 3025);
DISPLAY 0.872340 (-73 3025);
PAINT GREEN (-73 3025);
DISPLAY INVISIBLE (-73 3025);
FORCEADD TAP..1
R 2
(-75 3075);
FORCEPROP 3 LASTPIN (-25 3075) SIG_NAME UPI_CPU0_CPU1_P2P2_DP<5>
J 0
(-15 3085);
DISPLAY 0.659574 (-15 3085);
PAINT MONO (-15 3085);
DISPLAY INVISIBLE (-15 3085);
FORCEPROP 1 LASTPIN (-25 3075) BN 5
J 2
(-13 3083);
DISPLAY 0.680851 (-13 3083);
PAINT GREEN (-13 3083);
FORCEPROP 2 LAST CDS_LIB standard
J 0
(-75 3075);
DISPLAY INVISIBLE (-75 3075);
FORCEPROP 1 LAST BODY_TYPE PLUMBING
J 2
(-75 3125);
DISPLAY 0.872340 (-75 3125);
PAINT GREEN (-75 3125);
DISPLAY INVISIBLE (-75 3125);
FORCEPROP 1 LAST HDL_TAP TRUE
J 2
(-400 2950);
DISPLAY 0.872340 (-400 2950);
DISPLAY INVISIBLE (-400 2950);
FORCEPROP 1 LAST PATH I33
J 2
(-73 3075);
DISPLAY 0.872340 (-73 3075);
PAINT GREEN (-73 3075);
DISPLAY INVISIBLE (-73 3075);
FORCEADD TAP..1
R 2
(-75 3175);
FORCEPROP 3 LASTPIN (-25 3175) SIG_NAME UPI_CPU0_CPU1_P2P2_DP<7>
J 0
(-15 3185);
DISPLAY 0.659574 (-15 3185);
PAINT MONO (-15 3185);
DISPLAY INVISIBLE (-15 3185);
FORCEPROP 1 LASTPIN (-25 3175) BN 7
J 2
(-13 3183);
DISPLAY 0.680851 (-13 3183);
PAINT GREEN (-13 3183);
FORCEPROP 2 LAST CDS_LIB standard
J 0
(-75 3175);
DISPLAY INVISIBLE (-75 3175);
FORCEPROP 1 LAST BODY_TYPE PLUMBING
J 2
(-75 3225);
DISPLAY 0.872340 (-75 3225);
PAINT GREEN (-75 3225);
DISPLAY INVISIBLE (-75 3225);
FORCEPROP 1 LAST HDL_TAP TRUE
J 2
(-400 3050);
DISPLAY 0.872340 (-400 3050);
DISPLAY INVISIBLE (-400 3050);
FORCEPROP 1 LAST PATH I34
J 2
(-73 3175);
DISPLAY 0.872340 (-73 3175);
PAINT GREEN (-73 3175);
DISPLAY INVISIBLE (-73 3175);
FORCEADD TAP..1
R 2
(-75 3125);
FORCEPROP 3 LASTPIN (-25 3125) SIG_NAME UPI_CPU0_CPU1_P2P2_DP<6>
J 0
(-15 3135);
DISPLAY 0.659574 (-15 3135);
PAINT MONO (-15 3135);
DISPLAY INVISIBLE (-15 3135);
FORCEPROP 1 LASTPIN (-25 3125) BN 6
J 2
(-13 3133);
DISPLAY 0.680851 (-13 3133);
PAINT GREEN (-13 3133);
FORCEPROP 2 LAST CDS_LIB standard
J 0
(-75 3125);
DISPLAY INVISIBLE (-75 3125);
FORCEPROP 1 LAST BODY_TYPE PLUMBING
J 2
(-75 3175);
DISPLAY 0.872340 (-75 3175);
PAINT GREEN (-75 3175);
DISPLAY INVISIBLE (-75 3175);
FORCEPROP 1 LAST HDL_TAP TRUE
J 2
(-400 3000);
DISPLAY 0.872340 (-400 3000);
DISPLAY INVISIBLE (-400 3000);
FORCEPROP 1 LAST PATH I35
J 2
(-73 3125);
DISPLAY 0.872340 (-73 3125);
PAINT GREEN (-73 3125);
DISPLAY INVISIBLE (-73 3125);
FORCEADD TAP..1
R 2
(-75 3225);
FORCEPROP 3 LASTPIN (-25 3225) SIG_NAME UPI_CPU0_CPU1_P2P2_DP<8>
J 0
(-15 3235);
DISPLAY 0.659574 (-15 3235);
PAINT MONO (-15 3235);
DISPLAY INVISIBLE (-15 3235);
FORCEPROP 1 LASTPIN (-25 3225) BN 8
J 2
(-13 3233);
DISPLAY 0.680851 (-13 3233);
PAINT GREEN (-13 3233);
FORCEPROP 2 LAST CDS_LIB standard
J 0
(-75 3225);
DISPLAY INVISIBLE (-75 3225);
FORCEPROP 1 LAST BODY_TYPE PLUMBING
J 2
(-75 3275);
DISPLAY 0.872340 (-75 3275);
PAINT GREEN (-75 3275);
DISPLAY INVISIBLE (-75 3275);
FORCEPROP 1 LAST HDL_TAP TRUE
J 2
(-400 3100);
DISPLAY 0.872340 (-400 3100);
DISPLAY INVISIBLE (-400 3100);
FORCEPROP 1 LAST PATH I36
J 2
(-73 3225);
DISPLAY 0.872340 (-73 3225);
PAINT GREEN (-73 3225);
DISPLAY INVISIBLE (-73 3225);
FORCEADD TAP..1
R 2
(-75 3275);
FORCEPROP 3 LASTPIN (-25 3275) SIG_NAME UPI_CPU0_CPU1_P2P2_DP<9>
J 0
(-15 3285);
DISPLAY 0.659574 (-15 3285);
PAINT MONO (-15 3285);
DISPLAY INVISIBLE (-15 3285);
FORCEPROP 1 LASTPIN (-25 3275) BN 9
J 2
(-13 3283);
DISPLAY 0.680851 (-13 3283);
PAINT GREEN (-13 3283);
FORCEPROP 2 LAST CDS_LIB standard
J 0
(-75 3275);
DISPLAY INVISIBLE (-75 3275);
FORCEPROP 1 LAST BODY_TYPE PLUMBING
J 2
(-75 3325);
DISPLAY 0.872340 (-75 3325);
PAINT GREEN (-75 3325);
DISPLAY INVISIBLE (-75 3325);
FORCEPROP 1 LAST HDL_TAP TRUE
J 2
(-400 3150);
DISPLAY 0.872340 (-400 3150);
DISPLAY INVISIBLE (-400 3150);
FORCEPROP 1 LAST PATH I37
J 2
(-73 3275);
DISPLAY 0.872340 (-73 3275);
PAINT GREEN (-73 3275);
DISPLAY INVISIBLE (-73 3275);
FORCEADD TAP..1
R 2
(-75 3325);
FORCEPROP 3 LASTPIN (-25 3325) SIG_NAME UPI_CPU0_CPU1_P2P2_DP<10>
J 0
(-15 3335);
DISPLAY 0.659574 (-15 3335);
PAINT MONO (-15 3335);
DISPLAY INVISIBLE (-15 3335);
FORCEPROP 1 LASTPIN (-25 3325) BN 10
J 2
(-13 3333);
DISPLAY 0.680851 (-13 3333);
PAINT GREEN (-13 3333);
FORCEPROP 2 LAST CDS_LIB standard
J 0
(-75 3325);
DISPLAY INVISIBLE (-75 3325);
FORCEPROP 1 LAST BODY_TYPE PLUMBING
J 2
(-75 3375);
DISPLAY 0.872340 (-75 3375);
PAINT GREEN (-75 3375);
DISPLAY INVISIBLE (-75 3375);
FORCEPROP 1 LAST HDL_TAP TRUE
J 2
(-400 3200);
DISPLAY 0.872340 (-400 3200);
DISPLAY INVISIBLE (-400 3200);
FORCEPROP 1 LAST PATH I38
J 2
(-73 3325);
DISPLAY 0.872340 (-73 3325);
PAINT GREEN (-73 3325);
DISPLAY INVISIBLE (-73 3325);
FORCEADD TAP..1
R 2
(-75 3375);
FORCEPROP 3 LASTPIN (-25 3375) SIG_NAME UPI_CPU0_CPU1_P2P2_DP<11>
J 0
(-15 3385);
DISPLAY 0.659574 (-15 3385);
PAINT MONO (-15 3385);
DISPLAY INVISIBLE (-15 3385);
FORCEPROP 1 LASTPIN (-25 3375) BN 11
J 2
(-13 3383);
DISPLAY 0.680851 (-13 3383);
PAINT GREEN (-13 3383);
FORCEPROP 2 LAST CDS_LIB standard
J 0
(-75 3375);
DISPLAY INVISIBLE (-75 3375);
FORCEPROP 1 LAST BODY_TYPE PLUMBING
J 2
(-75 3425);
DISPLAY 0.872340 (-75 3425);
PAINT GREEN (-75 3425);
DISPLAY INVISIBLE (-75 3425);
FORCEPROP 1 LAST HDL_TAP TRUE
J 2
(-400 3250);
DISPLAY 0.872340 (-400 3250);
DISPLAY INVISIBLE (-400 3250);
FORCEPROP 1 LAST PATH I39
J 2
(-73 3375);
DISPLAY 0.872340 (-73 3375);
PAINT GREEN (-73 3375);
DISPLAY INVISIBLE (-73 3375);
FORCEADD TAP..1
R 2
(-75 1675);
FORCEPROP 3 LASTPIN (-25 1675) SIG_NAME UPI_CPU0_CPU1_P2P2_DN<2>
J 0
(-15 1685);
DISPLAY 0.659574 (-15 1685);
PAINT MONO (-15 1685);
DISPLAY INVISIBLE (-15 1685);
FORCEPROP 1 LASTPIN (-25 1675) BN 2
J 2
(-13 1683);
DISPLAY 0.680851 (-13 1683);
PAINT GREEN (-13 1683);
FORCEPROP 2 LAST CDS_LIB standard
J 0
(-75 1675);
DISPLAY INVISIBLE (-75 1675);
FORCEPROP 1 LAST BODY_TYPE PLUMBING
J 2
(-75 1725);
DISPLAY 0.872340 (-75 1725);
PAINT GREEN (-75 1725);
DISPLAY INVISIBLE (-75 1725);
FORCEPROP 1 LAST HDL_TAP TRUE
J 2
(-400 1550);
DISPLAY 0.872340 (-400 1550);
DISPLAY INVISIBLE (-400 1550);
FORCEPROP 1 LAST PATH I4
J 2
(-73 1675);
DISPLAY 0.872340 (-73 1675);
PAINT GREEN (-73 1675);
DISPLAY INVISIBLE (-73 1675);
FORCEADD TAP..1
R 2
(-75 3425);
FORCEPROP 3 LASTPIN (-25 3425) SIG_NAME UPI_CPU0_CPU1_P2P2_DP<12>
J 0
(-15 3435);
DISPLAY 0.659574 (-15 3435);
PAINT MONO (-15 3435);
DISPLAY INVISIBLE (-15 3435);
FORCEPROP 1 LASTPIN (-25 3425) BN 12
J 2
(-13 3433);
DISPLAY 0.680851 (-13 3433);
PAINT GREEN (-13 3433);
FORCEPROP 2 LAST CDS_LIB standard
J 0
(-75 3425);
DISPLAY INVISIBLE (-75 3425);
FORCEPROP 1 LAST BODY_TYPE PLUMBING
J 2
(-75 3475);
DISPLAY 0.872340 (-75 3475);
PAINT GREEN (-75 3475);
DISPLAY INVISIBLE (-75 3475);
FORCEPROP 1 LAST HDL_TAP TRUE
J 2
(-400 3300);
DISPLAY 0.872340 (-400 3300);
DISPLAY INVISIBLE (-400 3300);
FORCEPROP 1 LAST PATH I40
J 2
(-73 3425);
DISPLAY 0.872340 (-73 3425);
PAINT GREEN (-73 3425);
DISPLAY INVISIBLE (-73 3425);
FORCEADD TAP..1
R 2
(-75 3475);
FORCEPROP 3 LASTPIN (-25 3475) SIG_NAME UPI_CPU0_CPU1_P2P2_DP<13>
J 0
(-15 3485);
DISPLAY 0.659574 (-15 3485);
PAINT MONO (-15 3485);
DISPLAY INVISIBLE (-15 3485);
FORCEPROP 1 LASTPIN (-25 3475) BN 13
J 2
(-13 3483);
DISPLAY 0.680851 (-13 3483);
PAINT GREEN (-13 3483);
FORCEPROP 2 LAST CDS_LIB standard
J 0
(-75 3475);
DISPLAY INVISIBLE (-75 3475);
FORCEPROP 1 LAST BODY_TYPE PLUMBING
J 2
(-75 3525);
DISPLAY 0.872340 (-75 3525);
PAINT GREEN (-75 3525);
DISPLAY INVISIBLE (-75 3525);
FORCEPROP 1 LAST HDL_TAP TRUE
J 2
(-400 3350);
DISPLAY 0.872340 (-400 3350);
DISPLAY INVISIBLE (-400 3350);
FORCEPROP 1 LAST PATH I41
J 2
(-73 3475);
DISPLAY 0.872340 (-73 3475);
PAINT GREEN (-73 3475);
DISPLAY INVISIBLE (-73 3475);
FORCEADD TAP..1
R 2
(-75 3525);
FORCEPROP 3 LASTPIN (-25 3525) SIG_NAME UPI_CPU0_CPU1_P2P2_DP<14>
J 0
(-15 3535);
DISPLAY 0.659574 (-15 3535);
PAINT MONO (-15 3535);
DISPLAY INVISIBLE (-15 3535);
FORCEPROP 1 LASTPIN (-25 3525) BN 14
J 2
(-13 3533);
DISPLAY 0.680851 (-13 3533);
PAINT GREEN (-13 3533);
FORCEPROP 2 LAST CDS_LIB standard
J 0
(-75 3525);
DISPLAY INVISIBLE (-75 3525);
FORCEPROP 1 LAST BODY_TYPE PLUMBING
J 2
(-75 3575);
DISPLAY 0.872340 (-75 3575);
PAINT GREEN (-75 3575);
DISPLAY INVISIBLE (-75 3575);
FORCEPROP 1 LAST HDL_TAP TRUE
J 2
(-400 3400);
DISPLAY 0.872340 (-400 3400);
DISPLAY INVISIBLE (-400 3400);
FORCEPROP 1 LAST PATH I42
J 2
(-73 3525);
DISPLAY 0.872340 (-73 3525);
PAINT GREEN (-73 3525);
DISPLAY INVISIBLE (-73 3525);
FORCEADD TAP..1
R 2
(-75 3575);
FORCEPROP 3 LASTPIN (-25 3575) SIG_NAME UPI_CPU0_CPU1_P2P2_DP<15>
J 0
(-15 3585);
DISPLAY 0.659574 (-15 3585);
PAINT MONO (-15 3585);
DISPLAY INVISIBLE (-15 3585);
FORCEPROP 1 LASTPIN (-25 3575) BN 15
J 2
(-13 3583);
DISPLAY 0.680851 (-13 3583);
PAINT GREEN (-13 3583);
FORCEPROP 2 LAST CDS_LIB standard
J 0
(-75 3575);
DISPLAY INVISIBLE (-75 3575);
FORCEPROP 1 LAST BODY_TYPE PLUMBING
J 2
(-75 3625);
DISPLAY 0.872340 (-75 3625);
PAINT GREEN (-75 3625);
DISPLAY INVISIBLE (-75 3625);
FORCEPROP 1 LAST HDL_TAP TRUE
J 2
(-400 3450);
DISPLAY 0.872340 (-400 3450);
DISPLAY INVISIBLE (-400 3450);
FORCEPROP 1 LAST PATH I43
J 2
(-73 3575);
DISPLAY 0.872340 (-73 3575);
PAINT GREEN (-73 3575);
DISPLAY INVISIBLE (-73 3575);
FORCEADD TAP..1
R 2
(-75 3625);
FORCEPROP 3 LASTPIN (-25 3625) SIG_NAME UPI_CPU0_CPU1_P2P2_DP<16>
J 0
(-15 3635);
DISPLAY 0.659574 (-15 3635);
PAINT MONO (-15 3635);
DISPLAY INVISIBLE (-15 3635);
FORCEPROP 1 LASTPIN (-25 3625) BN 16
J 2
(-13 3633);
DISPLAY 0.680851 (-13 3633);
PAINT GREEN (-13 3633);
FORCEPROP 2 LAST CDS_LIB standard
J 0
(-75 3625);
DISPLAY INVISIBLE (-75 3625);
FORCEPROP 1 LAST BODY_TYPE PLUMBING
J 2
(-75 3675);
DISPLAY 0.872340 (-75 3675);
PAINT GREEN (-75 3675);
DISPLAY INVISIBLE (-75 3675);
FORCEPROP 1 LAST HDL_TAP TRUE
J 2
(-400 3500);
DISPLAY 0.872340 (-400 3500);
DISPLAY INVISIBLE (-400 3500);
FORCEPROP 1 LAST PATH I44
J 2
(-73 3625);
DISPLAY 0.872340 (-73 3625);
PAINT GREEN (-73 3625);
DISPLAY INVISIBLE (-73 3625);
FORCEADD TAP..1
R 2
(-75 3675);
FORCEPROP 3 LASTPIN (-25 3675) SIG_NAME UPI_CPU0_CPU1_P2P2_DP<17>
J 0
(-15 3685);
DISPLAY 0.659574 (-15 3685);
PAINT MONO (-15 3685);
DISPLAY INVISIBLE (-15 3685);
FORCEPROP 1 LASTPIN (-25 3675) BN 17
J 2
(-13 3683);
DISPLAY 0.680851 (-13 3683);
PAINT GREEN (-13 3683);
FORCEPROP 2 LAST CDS_LIB standard
J 0
(-75 3675);
DISPLAY INVISIBLE (-75 3675);
FORCEPROP 1 LAST BODY_TYPE PLUMBING
J 2
(-75 3725);
DISPLAY 0.872340 (-75 3725);
PAINT GREEN (-75 3725);
DISPLAY INVISIBLE (-75 3725);
FORCEPROP 1 LAST HDL_TAP TRUE
J 2
(-400 3550);
DISPLAY 0.872340 (-400 3550);
DISPLAY INVISIBLE (-400 3550);
FORCEPROP 1 LAST PATH I45
J 2
(-73 3675);
DISPLAY 0.872340 (-73 3675);
PAINT GREEN (-73 3675);
DISPLAY INVISIBLE (-73 3675);
FORCEADD TAP..1
R 2
(-75 3725);
FORCEPROP 3 LASTPIN (-25 3725) SIG_NAME UPI_CPU0_CPU1_P2P2_DP<18>
J 0
(-15 3735);
DISPLAY 0.659574 (-15 3735);
PAINT MONO (-15 3735);
DISPLAY INVISIBLE (-15 3735);
FORCEPROP 1 LASTPIN (-25 3725) BN 18
J 2
(-13 3733);
DISPLAY 0.680851 (-13 3733);
PAINT GREEN (-13 3733);
FORCEPROP 2 LAST CDS_LIB standard
J 0
(-75 3725);
DISPLAY INVISIBLE (-75 3725);
FORCEPROP 1 LAST BODY_TYPE PLUMBING
J 2
(-75 3775);
DISPLAY 0.872340 (-75 3775);
PAINT GREEN (-75 3775);
DISPLAY INVISIBLE (-75 3775);
FORCEPROP 1 LAST HDL_TAP TRUE
J 2
(-400 3600);
DISPLAY 0.872340 (-400 3600);
DISPLAY INVISIBLE (-400 3600);
FORCEPROP 1 LAST PATH I46
J 2
(-73 3725);
DISPLAY 0.872340 (-73 3725);
PAINT GREEN (-73 3725);
DISPLAY INVISIBLE (-73 3725);
FORCEADD TAP..1
R 2
(-75 3775);
FORCEPROP 3 LASTPIN (-25 3775) SIG_NAME UPI_CPU0_CPU1_P2P2_DP<19>
J 0
(-15 3785);
DISPLAY 0.659574 (-15 3785);
PAINT MONO (-15 3785);
DISPLAY INVISIBLE (-15 3785);
FORCEPROP 1 LASTPIN (-25 3775) BN 19
J 2
(-13 3783);
DISPLAY 0.680851 (-13 3783);
PAINT GREEN (-13 3783);
FORCEPROP 2 LAST CDS_LIB standard
J 0
(-75 3775);
DISPLAY INVISIBLE (-75 3775);
FORCEPROP 1 LAST BODY_TYPE PLUMBING
J 2
(-75 3825);
DISPLAY 0.872340 (-75 3825);
PAINT GREEN (-75 3825);
DISPLAY INVISIBLE (-75 3825);
FORCEPROP 1 LAST HDL_TAP TRUE
J 2
(-400 3650);
DISPLAY 0.872340 (-400 3650);
DISPLAY INVISIBLE (-400 3650);
FORCEPROP 1 LAST PATH I47
J 2
(-73 3775);
DISPLAY 0.872340 (-73 3775);
PAINT GREEN (-73 3775);
DISPLAY INVISIBLE (-73 3775);
FORCEADD TAP..1
R 2
(-75 3825);
FORCEPROP 3 LASTPIN (-25 3825) SIG_NAME UPI_CPU0_CPU1_P2P2_DP<20>
J 0
(-15 3835);
DISPLAY 0.659574 (-15 3835);
PAINT MONO (-15 3835);
DISPLAY INVISIBLE (-15 3835);
FORCEPROP 1 LASTPIN (-25 3825) BN 20
J 2
(-13 3833);
DISPLAY 0.680851 (-13 3833);
PAINT GREEN (-13 3833);
FORCEPROP 2 LAST CDS_LIB standard
J 0
(-75 3825);
DISPLAY INVISIBLE (-75 3825);
FORCEPROP 1 LAST BODY_TYPE PLUMBING
J 2
(-75 3875);
DISPLAY 0.872340 (-75 3875);
PAINT GREEN (-75 3875);
DISPLAY INVISIBLE (-75 3875);
FORCEPROP 1 LAST HDL_TAP TRUE
J 2
(-400 3700);
DISPLAY 0.872340 (-400 3700);
DISPLAY INVISIBLE (-400 3700);
FORCEPROP 1 LAST PATH I48
J 2
(-73 3825);
DISPLAY 0.872340 (-73 3825);
PAINT GREEN (-73 3825);
DISPLAY INVISIBLE (-73 3825);
FORCEADD TAP..1
R 2
(-75 3875);
FORCEPROP 3 LASTPIN (-25 3875) SIG_NAME UPI_CPU0_CPU1_P2P2_DP<21>
J 0
(-15 3885);
DISPLAY 0.659574 (-15 3885);
PAINT MONO (-15 3885);
DISPLAY INVISIBLE (-15 3885);
FORCEPROP 1 LASTPIN (-25 3875) BN 21
J 2
(-13 3883);
DISPLAY 0.680851 (-13 3883);
PAINT GREEN (-13 3883);
FORCEPROP 2 LAST CDS_LIB standard
J 0
(-75 3875);
DISPLAY INVISIBLE (-75 3875);
FORCEPROP 1 LAST BODY_TYPE PLUMBING
J 2
(-75 3925);
DISPLAY 0.872340 (-75 3925);
PAINT GREEN (-75 3925);
DISPLAY INVISIBLE (-75 3925);
FORCEPROP 1 LAST HDL_TAP TRUE
J 2
(-400 3750);
DISPLAY 0.872340 (-400 3750);
DISPLAY INVISIBLE (-400 3750);
FORCEPROP 1 LAST PATH I49
J 2
(-73 3875);
DISPLAY 0.872340 (-73 3875);
PAINT GREEN (-73 3875);
DISPLAY INVISIBLE (-73 3875);
FORCEADD TAP..1
R 2
(-75 1625);
FORCEPROP 3 LASTPIN (-25 1625) SIG_NAME UPI_CPU0_CPU1_P2P2_DN<1>
J 0
(-15 1635);
DISPLAY 0.659574 (-15 1635);
PAINT MONO (-15 1635);
DISPLAY INVISIBLE (-15 1635);
FORCEPROP 1 LASTPIN (-25 1625) BN 1
J 2
(-13 1633);
DISPLAY 0.680851 (-13 1633);
PAINT GREEN (-13 1633);
FORCEPROP 2 LAST CDS_LIB standard
J 0
(-75 1625);
DISPLAY INVISIBLE (-75 1625);
FORCEPROP 1 LAST BODY_TYPE PLUMBING
J 2
(-75 1675);
DISPLAY 0.872340 (-75 1675);
PAINT GREEN (-75 1675);
DISPLAY INVISIBLE (-75 1675);
FORCEPROP 1 LAST HDL_TAP TRUE
J 2
(-400 1500);
DISPLAY 0.872340 (-400 1500);
DISPLAY INVISIBLE (-400 1500);
FORCEPROP 1 LAST PATH I5
J 2
(-73 1625);
DISPLAY 0.872340 (-73 1625);
PAINT GREEN (-73 1625);
DISPLAY INVISIBLE (-73 1625);
FORCEADD TAP..1
R 2
(-75 3925);
FORCEPROP 3 LASTPIN (-25 3925) SIG_NAME UPI_CPU0_CPU1_P2P2_DP<22>
J 0
(-15 3935);
DISPLAY 0.659574 (-15 3935);
PAINT MONO (-15 3935);
DISPLAY INVISIBLE (-15 3935);
FORCEPROP 1 LASTPIN (-25 3925) BN 22
J 2
(-13 3933);
DISPLAY 0.680851 (-13 3933);
PAINT GREEN (-13 3933);
FORCEPROP 2 LAST CDS_LIB standard
J 0
(-75 3925);
DISPLAY INVISIBLE (-75 3925);
FORCEPROP 1 LAST BODY_TYPE PLUMBING
J 2
(-75 3975);
DISPLAY 0.872340 (-75 3975);
PAINT GREEN (-75 3975);
DISPLAY INVISIBLE (-75 3975);
FORCEPROP 1 LAST HDL_TAP TRUE
J 2
(-400 3800);
DISPLAY 0.872340 (-400 3800);
DISPLAY INVISIBLE (-400 3800);
FORCEPROP 1 LAST PATH I50
J 2
(-73 3925);
DISPLAY 0.872340 (-73 3925);
PAINT GREEN (-73 3925);
DISPLAY INVISIBLE (-73 3925);
FORCEADD TAP..1
R 2
(-75 3975);
FORCEPROP 3 LASTPIN (-25 3975) SIG_NAME UPI_CPU0_CPU1_P2P2_DP<23>
J 0
(-15 3985);
DISPLAY 0.659574 (-15 3985);
PAINT MONO (-15 3985);
DISPLAY INVISIBLE (-15 3985);
FORCEPROP 1 LASTPIN (-25 3975) BN 23
J 2
(-13 3983);
DISPLAY 0.680851 (-13 3983);
PAINT GREEN (-13 3983);
FORCEPROP 2 LAST CDS_LIB standard
J 0
(-75 3975);
DISPLAY INVISIBLE (-75 3975);
FORCEPROP 1 LAST BODY_TYPE PLUMBING
J 2
(-75 4025);
DISPLAY 0.872340 (-75 4025);
PAINT GREEN (-75 4025);
DISPLAY INVISIBLE (-75 4025);
FORCEPROP 1 LAST HDL_TAP TRUE
J 2
(-400 3850);
DISPLAY 0.872340 (-400 3850);
DISPLAY INVISIBLE (-400 3850);
FORCEPROP 1 LAST PATH I51
J 2
(-73 3975);
DISPLAY 0.872340 (-73 3975);
PAINT GREEN (-73 3975);
DISPLAY INVISIBLE (-73 3975);
FORCEADD TAP..1
(3300 1675);
FORCEPROP 3 LASTPIN (3250 1675) SIG_NAME UPI_CPU1_CPU0_P2P2_DN<2>
J 0
(3260 1685);
DISPLAY 0.659574 (3260 1685);
PAINT MONO (3260 1685);
DISPLAY INVISIBLE (3260 1685);
FORCEPROP 1 LASTPIN (3250 1675) BN 2
J 0
(3238 1683);
DISPLAY 0.680851 (3238 1683);
PAINT GREEN (3238 1683);
FORCEPROP 2 LAST CDS_LIB standard
J 0
(3300 1675);
PAINT MONO (3300 1675);
DISPLAY INVISIBLE (3300 1675);
FORCEPROP 1 LAST BODY_TYPE PLUMBING
J 0
(3300 1725);
DISPLAY 0.872340 (3300 1725);
PAINT GREEN (3300 1725);
DISPLAY INVISIBLE (3300 1725);
FORCEPROP 1 LAST HDL_TAP TRUE
J 0
(3625 1550);
DISPLAY 0.872340 (3625 1550);
DISPLAY INVISIBLE (3625 1550);
FORCEPROP 1 LAST PATH I52
J 0
(3298 1675);
DISPLAY 0.872340 (3298 1675);
PAINT GREEN (3298 1675);
DISPLAY INVISIBLE (3298 1675);
FORCEADD TAP..1
(3300 1625);
FORCEPROP 3 LASTPIN (3250 1625) SIG_NAME UPI_CPU1_CPU0_P2P2_DN<1>
J 0
(3260 1635);
DISPLAY 0.659574 (3260 1635);
PAINT MONO (3260 1635);
DISPLAY INVISIBLE (3260 1635);
FORCEPROP 1 LASTPIN (3250 1625) BN 1
J 0
(3238 1633);
DISPLAY 0.680851 (3238 1633);
PAINT GREEN (3238 1633);
FORCEPROP 2 LAST CDS_LIB standard
J 0
(3300 1625);
PAINT MONO (3300 1625);
DISPLAY INVISIBLE (3300 1625);
FORCEPROP 1 LAST BODY_TYPE PLUMBING
J 0
(3300 1675);
DISPLAY 0.872340 (3300 1675);
PAINT GREEN (3300 1675);
DISPLAY INVISIBLE (3300 1675);
FORCEPROP 1 LAST HDL_TAP TRUE
J 0
(3625 1500);
DISPLAY 0.872340 (3625 1500);
DISPLAY INVISIBLE (3625 1500);
FORCEPROP 1 LAST PATH I53
J 0
(3298 1625);
DISPLAY 0.872340 (3298 1625);
PAINT GREEN (3298 1625);
DISPLAY INVISIBLE (3298 1625);
FORCEADD TAP..1
(3300 1575);
FORCEPROP 3 LASTPIN (3250 1575) SIG_NAME UPI_CPU1_CPU0_P2P2_DN<0>
J 0
(3260 1585);
DISPLAY 0.659574 (3260 1585);
PAINT MONO (3260 1585);
DISPLAY INVISIBLE (3260 1585);
FORCEPROP 1 LASTPIN (3250 1575) BN 0
J 0
(3238 1583);
DISPLAY 0.680851 (3238 1583);
PAINT GREEN (3238 1583);
FORCEPROP 2 LAST CDS_LIB standard
J 0
(3300 1575);
PAINT MONO (3300 1575);
DISPLAY INVISIBLE (3300 1575);
FORCEPROP 1 LAST BODY_TYPE PLUMBING
J 0
(3300 1625);
DISPLAY 0.872340 (3300 1625);
PAINT GREEN (3300 1625);
DISPLAY INVISIBLE (3300 1625);
FORCEPROP 1 LAST HDL_TAP TRUE
J 0
(3625 1450);
DISPLAY 0.872340 (3625 1450);
DISPLAY INVISIBLE (3625 1450);
FORCEPROP 1 LAST PATH I54
J 0
(3298 1575);
DISPLAY 0.872340 (3298 1575);
PAINT GREEN (3298 1575);
DISPLAY INVISIBLE (3298 1575);
FORCEADD TAP..1
(3300 1775);
FORCEPROP 3 LASTPIN (3250 1775) SIG_NAME UPI_CPU1_CPU0_P2P2_DN<4>
J 0
(3260 1785);
DISPLAY 0.659574 (3260 1785);
PAINT MONO (3260 1785);
DISPLAY INVISIBLE (3260 1785);
FORCEPROP 1 LASTPIN (3250 1775) BN 4
J 0
(3238 1783);
DISPLAY 0.680851 (3238 1783);
PAINT GREEN (3238 1783);
FORCEPROP 2 LAST CDS_LIB standard
J 0
(3300 1775);
PAINT MONO (3300 1775);
DISPLAY INVISIBLE (3300 1775);
FORCEPROP 1 LAST BODY_TYPE PLUMBING
J 0
(3300 1825);
DISPLAY 0.872340 (3300 1825);
PAINT GREEN (3300 1825);
DISPLAY INVISIBLE (3300 1825);
FORCEPROP 1 LAST HDL_TAP TRUE
J 0
(3625 1650);
DISPLAY 0.872340 (3625 1650);
DISPLAY INVISIBLE (3625 1650);
FORCEPROP 1 LAST PATH I55
J 0
(3298 1775);
DISPLAY 0.872340 (3298 1775);
PAINT GREEN (3298 1775);
DISPLAY INVISIBLE (3298 1775);
FORCEADD TAP..1
(3300 1825);
FORCEPROP 3 LASTPIN (3250 1825) SIG_NAME UPI_CPU1_CPU0_P2P2_DN<5>
J 0
(3260 1835);
DISPLAY 0.659574 (3260 1835);
PAINT MONO (3260 1835);
DISPLAY INVISIBLE (3260 1835);
FORCEPROP 1 LASTPIN (3250 1825) BN 5
J 0
(3238 1833);
DISPLAY 0.680851 (3238 1833);
PAINT GREEN (3238 1833);
FORCEPROP 2 LAST CDS_LIB standard
J 0
(3300 1825);
PAINT MONO (3300 1825);
DISPLAY INVISIBLE (3300 1825);
FORCEPROP 1 LAST BODY_TYPE PLUMBING
J 0
(3300 1875);
DISPLAY 0.872340 (3300 1875);
PAINT GREEN (3300 1875);
DISPLAY INVISIBLE (3300 1875);
FORCEPROP 1 LAST HDL_TAP TRUE
J 0
(3625 1700);
DISPLAY 0.872340 (3625 1700);
DISPLAY INVISIBLE (3625 1700);
FORCEPROP 1 LAST PATH I56
J 0
(3298 1825);
DISPLAY 0.872340 (3298 1825);
PAINT GREEN (3298 1825);
DISPLAY INVISIBLE (3298 1825);
FORCEADD TAP..1
(3300 1725);
FORCEPROP 3 LASTPIN (3250 1725) SIG_NAME UPI_CPU1_CPU0_P2P2_DN<3>
J 0
(3260 1735);
DISPLAY 0.659574 (3260 1735);
PAINT MONO (3260 1735);
DISPLAY INVISIBLE (3260 1735);
FORCEPROP 1 LASTPIN (3250 1725) BN 3
J 0
(3238 1733);
DISPLAY 0.680851 (3238 1733);
PAINT GREEN (3238 1733);
FORCEPROP 2 LAST CDS_LIB standard
J 0
(3300 1725);
PAINT MONO (3300 1725);
DISPLAY INVISIBLE (3300 1725);
FORCEPROP 1 LAST BODY_TYPE PLUMBING
J 0
(3300 1775);
DISPLAY 0.872340 (3300 1775);
PAINT GREEN (3300 1775);
DISPLAY INVISIBLE (3300 1775);
FORCEPROP 1 LAST HDL_TAP TRUE
J 0
(3625 1600);
DISPLAY 0.872340 (3625 1600);
DISPLAY INVISIBLE (3625 1600);
FORCEPROP 1 LAST PATH I57
J 0
(3298 1725);
DISPLAY 0.872340 (3298 1725);
PAINT GREEN (3298 1725);
DISPLAY INVISIBLE (3298 1725);
FORCEADD TAP..1
(3300 1925);
FORCEPROP 3 LASTPIN (3250 1925) SIG_NAME UPI_CPU1_CPU0_P2P2_DN<7>
J 0
(3260 1935);
DISPLAY 0.659574 (3260 1935);
PAINT MONO (3260 1935);
DISPLAY INVISIBLE (3260 1935);
FORCEPROP 1 LASTPIN (3250 1925) BN 7
J 0
(3238 1933);
DISPLAY 0.680851 (3238 1933);
PAINT GREEN (3238 1933);
FORCEPROP 2 LAST CDS_LIB standard
J 0
(3300 1925);
PAINT MONO (3300 1925);
DISPLAY INVISIBLE (3300 1925);
FORCEPROP 1 LAST BODY_TYPE PLUMBING
J 0
(3300 1975);
DISPLAY 0.872340 (3300 1975);
PAINT GREEN (3300 1975);
DISPLAY INVISIBLE (3300 1975);
FORCEPROP 1 LAST HDL_TAP TRUE
J 0
(3625 1800);
DISPLAY 0.872340 (3625 1800);
DISPLAY INVISIBLE (3625 1800);
FORCEPROP 1 LAST PATH I58
J 0
(3298 1925);
DISPLAY 0.872340 (3298 1925);
PAINT GREEN (3298 1925);
DISPLAY INVISIBLE (3298 1925);
FORCEADD TAP..1
(3300 1875);
FORCEPROP 3 LASTPIN (3250 1875) SIG_NAME UPI_CPU1_CPU0_P2P2_DN<6>
J 0
(3260 1885);
DISPLAY 0.659574 (3260 1885);
PAINT MONO (3260 1885);
DISPLAY INVISIBLE (3260 1885);
FORCEPROP 1 LASTPIN (3250 1875) BN 6
J 0
(3238 1883);
DISPLAY 0.680851 (3238 1883);
PAINT GREEN (3238 1883);
FORCEPROP 2 LAST CDS_LIB standard
J 0
(3300 1875);
PAINT MONO (3300 1875);
DISPLAY INVISIBLE (3300 1875);
FORCEPROP 1 LAST BODY_TYPE PLUMBING
J 0
(3300 1925);
DISPLAY 0.872340 (3300 1925);
PAINT GREEN (3300 1925);
DISPLAY INVISIBLE (3300 1925);
FORCEPROP 1 LAST HDL_TAP TRUE
J 0
(3625 1750);
DISPLAY 0.872340 (3625 1750);
DISPLAY INVISIBLE (3625 1750);
FORCEPROP 1 LAST PATH I59
J 0
(3298 1875);
DISPLAY 0.872340 (3298 1875);
PAINT GREEN (3298 1875);
DISPLAY INVISIBLE (3298 1875);
FORCEADD TAP..1
R 2
(-75 1725);
FORCEPROP 3 LASTPIN (-25 1725) SIG_NAME UPI_CPU0_CPU1_P2P2_DN<3>
J 0
(-15 1735);
DISPLAY 0.659574 (-15 1735);
PAINT MONO (-15 1735);
DISPLAY INVISIBLE (-15 1735);
FORCEPROP 1 LASTPIN (-25 1725) BN 3
J 2
(-13 1733);
DISPLAY 0.680851 (-13 1733);
PAINT GREEN (-13 1733);
FORCEPROP 2 LAST CDS_LIB standard
J 0
(-75 1725);
DISPLAY INVISIBLE (-75 1725);
FORCEPROP 1 LAST BODY_TYPE PLUMBING
J 2
(-75 1775);
DISPLAY 0.872340 (-75 1775);
PAINT GREEN (-75 1775);
DISPLAY INVISIBLE (-75 1775);
FORCEPROP 1 LAST HDL_TAP TRUE
J 2
(-400 1600);
DISPLAY 0.872340 (-400 1600);
DISPLAY INVISIBLE (-400 1600);
FORCEPROP 1 LAST PATH I6
J 2
(-73 1725);
DISPLAY 0.872340 (-73 1725);
PAINT GREEN (-73 1725);
DISPLAY INVISIBLE (-73 1725);
FORCEADD TAP..1
(3300 2075);
FORCEPROP 3 LASTPIN (3250 2075) SIG_NAME UPI_CPU1_CPU0_P2P2_DN<10>
J 0
(3260 2085);
DISPLAY 0.659574 (3260 2085);
PAINT MONO (3260 2085);
DISPLAY INVISIBLE (3260 2085);
FORCEPROP 1 LASTPIN (3250 2075) BN 10
J 0
(3238 2083);
DISPLAY 0.680851 (3238 2083);
PAINT GREEN (3238 2083);
FORCEPROP 2 LAST CDS_LIB standard
J 0
(3300 2075);
PAINT MONO (3300 2075);
DISPLAY INVISIBLE (3300 2075);
FORCEPROP 1 LAST BODY_TYPE PLUMBING
J 0
(3300 2125);
DISPLAY 0.872340 (3300 2125);
PAINT GREEN (3300 2125);
DISPLAY INVISIBLE (3300 2125);
FORCEPROP 1 LAST HDL_TAP TRUE
J 0
(3625 1950);
DISPLAY 0.872340 (3625 1950);
DISPLAY INVISIBLE (3625 1950);
FORCEPROP 1 LAST PATH I60
J 0
(3298 2075);
DISPLAY 0.872340 (3298 2075);
PAINT GREEN (3298 2075);
DISPLAY INVISIBLE (3298 2075);
FORCEADD TAP..1
(3300 2025);
FORCEPROP 3 LASTPIN (3250 2025) SIG_NAME UPI_CPU1_CPU0_P2P2_DN<9>
J 0
(3260 2035);
DISPLAY 0.659574 (3260 2035);
PAINT MONO (3260 2035);
DISPLAY INVISIBLE (3260 2035);
FORCEPROP 1 LASTPIN (3250 2025) BN 9
J 0
(3238 2033);
DISPLAY 0.680851 (3238 2033);
PAINT GREEN (3238 2033);
FORCEPROP 2 LAST CDS_LIB standard
J 0
(3300 2025);
PAINT MONO (3300 2025);
DISPLAY INVISIBLE (3300 2025);
FORCEPROP 1 LAST BODY_TYPE PLUMBING
J 0
(3300 2075);
DISPLAY 0.872340 (3300 2075);
PAINT GREEN (3300 2075);
DISPLAY INVISIBLE (3300 2075);
FORCEPROP 1 LAST HDL_TAP TRUE
J 0
(3625 1900);
DISPLAY 0.872340 (3625 1900);
DISPLAY INVISIBLE (3625 1900);
FORCEPROP 1 LAST PATH I61
J 0
(3298 2025);
DISPLAY 0.872340 (3298 2025);
PAINT GREEN (3298 2025);
DISPLAY INVISIBLE (3298 2025);
FORCEADD TAP..1
(3300 1975);
FORCEPROP 3 LASTPIN (3250 1975) SIG_NAME UPI_CPU1_CPU0_P2P2_DN<8>
J 0
(3260 1985);
DISPLAY 0.659574 (3260 1985);
PAINT MONO (3260 1985);
DISPLAY INVISIBLE (3260 1985);
FORCEPROP 1 LASTPIN (3250 1975) BN 8
J 0
(3238 1983);
DISPLAY 0.680851 (3238 1983);
PAINT GREEN (3238 1983);
FORCEPROP 2 LAST CDS_LIB standard
J 0
(3300 1975);
PAINT MONO (3300 1975);
DISPLAY INVISIBLE (3300 1975);
FORCEPROP 1 LAST BODY_TYPE PLUMBING
J 0
(3300 2025);
DISPLAY 0.872340 (3300 2025);
PAINT GREEN (3300 2025);
DISPLAY INVISIBLE (3300 2025);
FORCEPROP 1 LAST HDL_TAP TRUE
J 0
(3625 1850);
DISPLAY 0.872340 (3625 1850);
DISPLAY INVISIBLE (3625 1850);
FORCEPROP 1 LAST PATH I62
J 0
(3298 1975);
DISPLAY 0.872340 (3298 1975);
PAINT GREEN (3298 1975);
DISPLAY INVISIBLE (3298 1975);
FORCEADD TAP..1
(3300 2175);
FORCEPROP 3 LASTPIN (3250 2175) SIG_NAME UPI_CPU1_CPU0_P2P2_DN<12>
J 0
(3260 2185);
DISPLAY 0.659574 (3260 2185);
PAINT MONO (3260 2185);
DISPLAY INVISIBLE (3260 2185);
FORCEPROP 1 LASTPIN (3250 2175) BN 12
J 0
(3238 2183);
DISPLAY 0.680851 (3238 2183);
PAINT GREEN (3238 2183);
FORCEPROP 2 LAST CDS_LIB standard
J 0
(3300 2175);
PAINT MONO (3300 2175);
DISPLAY INVISIBLE (3300 2175);
FORCEPROP 1 LAST BODY_TYPE PLUMBING
J 0
(3300 2225);
DISPLAY 0.872340 (3300 2225);
PAINT GREEN (3300 2225);
DISPLAY INVISIBLE (3300 2225);
FORCEPROP 1 LAST HDL_TAP TRUE
J 0
(3625 2050);
DISPLAY 0.872340 (3625 2050);
DISPLAY INVISIBLE (3625 2050);
FORCEPROP 1 LAST PATH I63
J 0
(3298 2175);
DISPLAY 0.872340 (3298 2175);
PAINT GREEN (3298 2175);
DISPLAY INVISIBLE (3298 2175);
FORCEADD TAP..1
(3300 2125);
FORCEPROP 3 LASTPIN (3250 2125) SIG_NAME UPI_CPU1_CPU0_P2P2_DN<11>
J 0
(3260 2135);
DISPLAY 0.659574 (3260 2135);
PAINT MONO (3260 2135);
DISPLAY INVISIBLE (3260 2135);
FORCEPROP 1 LASTPIN (3250 2125) BN 11
J 0
(3238 2133);
DISPLAY 0.680851 (3238 2133);
PAINT GREEN (3238 2133);
FORCEPROP 2 LAST CDS_LIB standard
J 0
(3300 2125);
PAINT MONO (3300 2125);
DISPLAY INVISIBLE (3300 2125);
FORCEPROP 1 LAST BODY_TYPE PLUMBING
J 0
(3300 2175);
DISPLAY 0.872340 (3300 2175);
PAINT GREEN (3300 2175);
DISPLAY INVISIBLE (3300 2175);
FORCEPROP 1 LAST HDL_TAP TRUE
J 0
(3625 2000);
DISPLAY 0.872340 (3625 2000);
DISPLAY INVISIBLE (3625 2000);
FORCEPROP 1 LAST PATH I64
J 0
(3298 2125);
DISPLAY 0.872340 (3298 2125);
PAINT GREEN (3298 2125);
DISPLAY INVISIBLE (3298 2125);
FORCEADD TAP..1
(3300 2225);
FORCEPROP 3 LASTPIN (3250 2225) SIG_NAME UPI_CPU1_CPU0_P2P2_DN<13>
J 0
(3260 2235);
DISPLAY 0.659574 (3260 2235);
PAINT MONO (3260 2235);
DISPLAY INVISIBLE (3260 2235);
FORCEPROP 1 LASTPIN (3250 2225) BN 13
J 0
(3238 2233);
DISPLAY 0.680851 (3238 2233);
PAINT GREEN (3238 2233);
FORCEPROP 2 LAST CDS_LIB standard
J 0
(3300 2225);
PAINT MONO (3300 2225);
DISPLAY INVISIBLE (3300 2225);
FORCEPROP 1 LAST BODY_TYPE PLUMBING
J 0
(3300 2275);
DISPLAY 0.872340 (3300 2275);
PAINT GREEN (3300 2275);
DISPLAY INVISIBLE (3300 2275);
FORCEPROP 1 LAST HDL_TAP TRUE
J 0
(3625 2100);
DISPLAY 0.872340 (3625 2100);
DISPLAY INVISIBLE (3625 2100);
FORCEPROP 1 LAST PATH I65
J 0
(3298 2225);
DISPLAY 0.872340 (3298 2225);
PAINT GREEN (3298 2225);
DISPLAY INVISIBLE (3298 2225);
FORCEADD TAP..1
(3300 2325);
FORCEPROP 3 LASTPIN (3250 2325) SIG_NAME UPI_CPU1_CPU0_P2P2_DN<15>
J 0
(3260 2335);
DISPLAY 0.659574 (3260 2335);
PAINT MONO (3260 2335);
DISPLAY INVISIBLE (3260 2335);
FORCEPROP 1 LASTPIN (3250 2325) BN 15
J 0
(3238 2333);
DISPLAY 0.680851 (3238 2333);
PAINT GREEN (3238 2333);
FORCEPROP 2 LAST CDS_LIB standard
J 0
(3300 2325);
PAINT MONO (3300 2325);
DISPLAY INVISIBLE (3300 2325);
FORCEPROP 1 LAST BODY_TYPE PLUMBING
J 0
(3300 2375);
DISPLAY 0.872340 (3300 2375);
PAINT GREEN (3300 2375);
DISPLAY INVISIBLE (3300 2375);
FORCEPROP 1 LAST HDL_TAP TRUE
J 0
(3625 2200);
DISPLAY 0.872340 (3625 2200);
DISPLAY INVISIBLE (3625 2200);
FORCEPROP 1 LAST PATH I66
J 0
(3298 2325);
DISPLAY 0.872340 (3298 2325);
PAINT GREEN (3298 2325);
DISPLAY INVISIBLE (3298 2325);
FORCEADD TAP..1
(3300 2275);
FORCEPROP 3 LASTPIN (3250 2275) SIG_NAME UPI_CPU1_CPU0_P2P2_DN<14>
J 0
(3260 2285);
DISPLAY 0.659574 (3260 2285);
PAINT MONO (3260 2285);
DISPLAY INVISIBLE (3260 2285);
FORCEPROP 1 LASTPIN (3250 2275) BN 14
J 0
(3238 2283);
DISPLAY 0.680851 (3238 2283);
PAINT GREEN (3238 2283);
FORCEPROP 2 LAST CDS_LIB standard
J 0
(3300 2275);
PAINT MONO (3300 2275);
DISPLAY INVISIBLE (3300 2275);
FORCEPROP 1 LAST BODY_TYPE PLUMBING
J 0
(3300 2325);
DISPLAY 0.872340 (3300 2325);
PAINT GREEN (3300 2325);
DISPLAY INVISIBLE (3300 2325);
FORCEPROP 1 LAST HDL_TAP TRUE
J 0
(3625 2150);
DISPLAY 0.872340 (3625 2150);
DISPLAY INVISIBLE (3625 2150);
FORCEPROP 1 LAST PATH I67
J 0
(3298 2275);
DISPLAY 0.872340 (3298 2275);
PAINT GREEN (3298 2275);
DISPLAY INVISIBLE (3298 2275);
FORCEADD TAP..1
(3300 2425);
FORCEPROP 3 LASTPIN (3250 2425) SIG_NAME UPI_CPU1_CPU0_P2P2_DN<17>
J 0
(3260 2435);
DISPLAY 0.659574 (3260 2435);
PAINT MONO (3260 2435);
DISPLAY INVISIBLE (3260 2435);
FORCEPROP 1 LASTPIN (3250 2425) BN 17
J 0
(3238 2433);
DISPLAY 0.680851 (3238 2433);
PAINT GREEN (3238 2433);
FORCEPROP 2 LAST CDS_LIB standard
J 0
(3300 2425);
DISPLAY INVISIBLE (3300 2425);
FORCEPROP 1 LAST BODY_TYPE PLUMBING
J 0
(3300 2475);
DISPLAY 0.872340 (3300 2475);
PAINT GREEN (3300 2475);
DISPLAY INVISIBLE (3300 2475);
FORCEPROP 1 LAST HDL_TAP TRUE
J 0
(3625 2300);
DISPLAY 0.872340 (3625 2300);
DISPLAY INVISIBLE (3625 2300);
FORCEPROP 1 LAST PATH I68
J 0
(3298 2425);
DISPLAY 0.872340 (3298 2425);
PAINT GREEN (3298 2425);
DISPLAY INVISIBLE (3298 2425);
FORCEADD TAP..1
(3300 2375);
FORCEPROP 3 LASTPIN (3250 2375) SIG_NAME UPI_CPU1_CPU0_P2P2_DN<16>
J 0
(3260 2385);
DISPLAY 0.659574 (3260 2385);
PAINT MONO (3260 2385);
DISPLAY INVISIBLE (3260 2385);
FORCEPROP 1 LASTPIN (3250 2375) BN 16
J 0
(3238 2383);
DISPLAY 0.680851 (3238 2383);
PAINT GREEN (3238 2383);
FORCEPROP 2 LAST CDS_LIB standard
J 0
(3300 2375);
PAINT MONO (3300 2375);
DISPLAY INVISIBLE (3300 2375);
FORCEPROP 1 LAST BODY_TYPE PLUMBING
J 0
(3300 2425);
DISPLAY 0.872340 (3300 2425);
PAINT GREEN (3300 2425);
DISPLAY INVISIBLE (3300 2425);
FORCEPROP 1 LAST HDL_TAP TRUE
J 0
(3625 2250);
DISPLAY 0.872340 (3625 2250);
DISPLAY INVISIBLE (3625 2250);
FORCEPROP 1 LAST PATH I69
J 0
(3298 2375);
DISPLAY 0.872340 (3298 2375);
PAINT GREEN (3298 2375);
DISPLAY INVISIBLE (3298 2375);
FORCEADD TAP..1
R 2
(-75 1775);
FORCEPROP 3 LASTPIN (-25 1775) SIG_NAME UPI_CPU0_CPU1_P2P2_DN<4>
J 0
(-15 1785);
DISPLAY 0.659574 (-15 1785);
PAINT MONO (-15 1785);
DISPLAY INVISIBLE (-15 1785);
FORCEPROP 1 LASTPIN (-25 1775) BN 4
J 2
(-13 1783);
DISPLAY 0.680851 (-13 1783);
PAINT GREEN (-13 1783);
FORCEPROP 2 LAST CDS_LIB standard
J 0
(-75 1775);
DISPLAY INVISIBLE (-75 1775);
FORCEPROP 1 LAST BODY_TYPE PLUMBING
J 2
(-75 1825);
DISPLAY 0.872340 (-75 1825);
PAINT GREEN (-75 1825);
DISPLAY INVISIBLE (-75 1825);
FORCEPROP 1 LAST HDL_TAP TRUE
J 2
(-400 1650);
DISPLAY 0.872340 (-400 1650);
DISPLAY INVISIBLE (-400 1650);
FORCEPROP 1 LAST PATH I7
J 2
(-73 1775);
DISPLAY 0.872340 (-73 1775);
PAINT GREEN (-73 1775);
DISPLAY INVISIBLE (-73 1775);
FORCEADD TAP..1
(3300 2475);
FORCEPROP 3 LASTPIN (3250 2475) SIG_NAME UPI_CPU1_CPU0_P2P2_DN<18>
J 0
(3260 2485);
DISPLAY 0.659574 (3260 2485);
PAINT MONO (3260 2485);
DISPLAY INVISIBLE (3260 2485);
FORCEPROP 1 LASTPIN (3250 2475) BN 18
J 0
(3238 2483);
DISPLAY 0.680851 (3238 2483);
PAINT GREEN (3238 2483);
FORCEPROP 2 LAST CDS_LIB standard
J 0
(3300 2475);
DISPLAY INVISIBLE (3300 2475);
FORCEPROP 1 LAST BODY_TYPE PLUMBING
J 0
(3300 2525);
DISPLAY 0.872340 (3300 2525);
PAINT GREEN (3300 2525);
DISPLAY INVISIBLE (3300 2525);
FORCEPROP 1 LAST HDL_TAP TRUE
J 0
(3625 2350);
DISPLAY 0.872340 (3625 2350);
DISPLAY INVISIBLE (3625 2350);
FORCEPROP 1 LAST PATH I70
J 0
(3298 2475);
DISPLAY 0.872340 (3298 2475);
PAINT GREEN (3298 2475);
DISPLAY INVISIBLE (3298 2475);
FORCEADD TAP..1
(3300 2725);
FORCEPROP 3 LASTPIN (3250 2725) SIG_NAME UPI_CPU1_CPU0_P2P2_DN<23>
J 0
(3260 2735);
DISPLAY 0.659574 (3260 2735);
PAINT MONO (3260 2735);
DISPLAY INVISIBLE (3260 2735);
FORCEPROP 1 LASTPIN (3250 2725) BN 23
J 0
(3238 2733);
DISPLAY 0.680851 (3238 2733);
PAINT GREEN (3238 2733);
FORCEPROP 2 LAST CDS_LIB standard
J 0
(3300 2725);
DISPLAY INVISIBLE (3300 2725);
FORCEPROP 1 LAST BODY_TYPE PLUMBING
J 0
(3300 2775);
DISPLAY 0.872340 (3300 2775);
PAINT GREEN (3300 2775);
DISPLAY INVISIBLE (3300 2775);
FORCEPROP 1 LAST HDL_TAP TRUE
J 0
(3625 2600);
DISPLAY 0.872340 (3625 2600);
DISPLAY INVISIBLE (3625 2600);
FORCEPROP 1 LAST PATH I71
J 0
(3298 2725);
DISPLAY 0.872340 (3298 2725);
PAINT GREEN (3298 2725);
DISPLAY INVISIBLE (3298 2725);
FORCEADD TAP..1
(3300 2675);
FORCEPROP 3 LASTPIN (3250 2675) SIG_NAME UPI_CPU1_CPU0_P2P2_DN<22>
J 0
(3260 2685);
DISPLAY 0.659574 (3260 2685);
PAINT MONO (3260 2685);
DISPLAY INVISIBLE (3260 2685);
FORCEPROP 1 LASTPIN (3250 2675) BN 22
J 0
(3238 2683);
DISPLAY 0.680851 (3238 2683);
PAINT GREEN (3238 2683);
FORCEPROP 2 LAST CDS_LIB standard
J 0
(3300 2675);
DISPLAY INVISIBLE (3300 2675);
FORCEPROP 1 LAST BODY_TYPE PLUMBING
J 0
(3300 2725);
DISPLAY 0.872340 (3300 2725);
PAINT GREEN (3300 2725);
DISPLAY INVISIBLE (3300 2725);
FORCEPROP 1 LAST HDL_TAP TRUE
J 0
(3625 2550);
DISPLAY 0.872340 (3625 2550);
DISPLAY INVISIBLE (3625 2550);
FORCEPROP 1 LAST PATH I72
J 0
(3298 2675);
DISPLAY 0.872340 (3298 2675);
PAINT GREEN (3298 2675);
DISPLAY INVISIBLE (3298 2675);
FORCEADD TAP..1
(3300 2625);
FORCEPROP 3 LASTPIN (3250 2625) SIG_NAME UPI_CPU1_CPU0_P2P2_DN<21>
J 0
(3260 2635);
DISPLAY 0.659574 (3260 2635);
PAINT MONO (3260 2635);
DISPLAY INVISIBLE (3260 2635);
FORCEPROP 1 LASTPIN (3250 2625) BN 21
J 0
(3238 2633);
DISPLAY 0.680851 (3238 2633);
PAINT GREEN (3238 2633);
FORCEPROP 2 LAST CDS_LIB standard
J 0
(3300 2625);
DISPLAY INVISIBLE (3300 2625);
FORCEPROP 1 LAST BODY_TYPE PLUMBING
J 0
(3300 2675);
DISPLAY 0.872340 (3300 2675);
PAINT GREEN (3300 2675);
DISPLAY INVISIBLE (3300 2675);
FORCEPROP 1 LAST HDL_TAP TRUE
J 0
(3625 2500);
DISPLAY 0.872340 (3625 2500);
DISPLAY INVISIBLE (3625 2500);
FORCEPROP 1 LAST PATH I73
J 0
(3298 2625);
DISPLAY 0.872340 (3298 2625);
PAINT GREEN (3298 2625);
DISPLAY INVISIBLE (3298 2625);
FORCEADD TAP..1
(3300 2575);
FORCEPROP 3 LASTPIN (3250 2575) SIG_NAME UPI_CPU1_CPU0_P2P2_DN<20>
J 0
(3260 2585);
DISPLAY 0.659574 (3260 2585);
PAINT MONO (3260 2585);
DISPLAY INVISIBLE (3260 2585);
FORCEPROP 1 LASTPIN (3250 2575) BN 20
J 0
(3238 2583);
DISPLAY 0.680851 (3238 2583);
PAINT GREEN (3238 2583);
FORCEPROP 2 LAST CDS_LIB standard
J 0
(3300 2575);
DISPLAY INVISIBLE (3300 2575);
FORCEPROP 1 LAST BODY_TYPE PLUMBING
J 0
(3300 2625);
DISPLAY 0.872340 (3300 2625);
PAINT GREEN (3300 2625);
DISPLAY INVISIBLE (3300 2625);
FORCEPROP 1 LAST HDL_TAP TRUE
J 0
(3625 2450);
DISPLAY 0.872340 (3625 2450);
DISPLAY INVISIBLE (3625 2450);
FORCEPROP 1 LAST PATH I74
J 0
(3298 2575);
DISPLAY 0.872340 (3298 2575);
PAINT GREEN (3298 2575);
DISPLAY INVISIBLE (3298 2575);
FORCEADD TAP..1
(3300 2525);
FORCEPROP 3 LASTPIN (3250 2525) SIG_NAME UPI_CPU1_CPU0_P2P2_DN<19>
J 0
(3260 2535);
DISPLAY 0.659574 (3260 2535);
PAINT MONO (3260 2535);
DISPLAY INVISIBLE (3260 2535);
FORCEPROP 1 LASTPIN (3250 2525) BN 19
J 0
(3238 2533);
DISPLAY 0.680851 (3238 2533);
PAINT GREEN (3238 2533);
FORCEPROP 2 LAST CDS_LIB standard
J 0
(3300 2525);
DISPLAY INVISIBLE (3300 2525);
FORCEPROP 1 LAST BODY_TYPE PLUMBING
J 0
(3300 2575);
DISPLAY 0.872340 (3300 2575);
PAINT GREEN (3300 2575);
DISPLAY INVISIBLE (3300 2575);
FORCEPROP 1 LAST HDL_TAP TRUE
J 0
(3625 2400);
DISPLAY 0.872340 (3625 2400);
DISPLAY INVISIBLE (3625 2400);
FORCEPROP 1 LAST PATH I75
J 0
(3298 2525);
DISPLAY 0.872340 (3298 2525);
PAINT GREEN (3298 2525);
DISPLAY INVISIBLE (3298 2525);
FORCEADD TAP..1
(3300 2925);
FORCEPROP 3 LASTPIN (3250 2925) SIG_NAME UPI_CPU1_CPU0_P2P2_DP<2>
J 0
(3260 2935);
DISPLAY 0.659574 (3260 2935);
PAINT MONO (3260 2935);
DISPLAY INVISIBLE (3260 2935);
FORCEPROP 1 LASTPIN (3250 2925) BN 2
J 0
(3238 2933);
DISPLAY 0.680851 (3238 2933);
PAINT GREEN (3238 2933);
FORCEPROP 2 LAST CDS_LIB standard
J 0
(3300 2925);
PAINT MONO (3300 2925);
DISPLAY INVISIBLE (3300 2925);
FORCEPROP 1 LAST BODY_TYPE PLUMBING
J 0
(3300 2975);
DISPLAY 0.872340 (3300 2975);
PAINT GREEN (3300 2975);
DISPLAY INVISIBLE (3300 2975);
FORCEPROP 1 LAST HDL_TAP TRUE
J 0
(3625 2800);
DISPLAY 0.872340 (3625 2800);
DISPLAY INVISIBLE (3625 2800);
FORCEPROP 1 LAST PATH I76
J 0
(3298 2925);
DISPLAY 0.872340 (3298 2925);
PAINT GREEN (3298 2925);
DISPLAY INVISIBLE (3298 2925);
FORCEADD TAP..1
(3300 2975);
FORCEPROP 3 LASTPIN (3250 2975) SIG_NAME UPI_CPU1_CPU0_P2P2_DP<3>
J 0
(3260 2985);
DISPLAY 0.659574 (3260 2985);
PAINT MONO (3260 2985);
DISPLAY INVISIBLE (3260 2985);
FORCEPROP 1 LASTPIN (3250 2975) BN 3
J 0
(3238 2983);
DISPLAY 0.680851 (3238 2983);
PAINT GREEN (3238 2983);
FORCEPROP 2 LAST CDS_LIB standard
J 0
(3300 2975);
PAINT MONO (3300 2975);
DISPLAY INVISIBLE (3300 2975);
FORCEPROP 1 LAST BODY_TYPE PLUMBING
J 0
(3300 3025);
DISPLAY 0.872340 (3300 3025);
PAINT GREEN (3300 3025);
DISPLAY INVISIBLE (3300 3025);
FORCEPROP 1 LAST HDL_TAP TRUE
J 0
(3625 2850);
DISPLAY 0.872340 (3625 2850);
DISPLAY INVISIBLE (3625 2850);
FORCEPROP 1 LAST PATH I77
J 0
(3298 2975);
DISPLAY 0.872340 (3298 2975);
PAINT GREEN (3298 2975);
DISPLAY INVISIBLE (3298 2975);
FORCEADD TAP..1
(3300 2875);
FORCEPROP 3 LASTPIN (3250 2875) SIG_NAME UPI_CPU1_CPU0_P2P2_DP<1>
J 0
(3260 2885);
DISPLAY 0.659574 (3260 2885);
PAINT MONO (3260 2885);
DISPLAY INVISIBLE (3260 2885);
FORCEPROP 1 LASTPIN (3250 2875) BN 1
J 0
(3238 2883);
DISPLAY 0.680851 (3238 2883);
PAINT GREEN (3238 2883);
FORCEPROP 2 LAST CDS_LIB standard
J 0
(3300 2875);
PAINT MONO (3300 2875);
DISPLAY INVISIBLE (3300 2875);
FORCEPROP 1 LAST BODY_TYPE PLUMBING
J 0
(3300 2925);
DISPLAY 0.872340 (3300 2925);
PAINT GREEN (3300 2925);
DISPLAY INVISIBLE (3300 2925);
FORCEPROP 1 LAST HDL_TAP TRUE
J 0
(3625 2750);
DISPLAY 0.872340 (3625 2750);
DISPLAY INVISIBLE (3625 2750);
FORCEPROP 1 LAST PATH I78
J 0
(3298 2875);
DISPLAY 0.872340 (3298 2875);
PAINT GREEN (3298 2875);
DISPLAY INVISIBLE (3298 2875);
FORCEADD TAP..1
(3300 2825);
FORCEPROP 3 LASTPIN (3250 2825) SIG_NAME UPI_CPU1_CPU0_P2P2_DP<0>
J 0
(3260 2835);
DISPLAY 0.659574 (3260 2835);
PAINT MONO (3260 2835);
DISPLAY INVISIBLE (3260 2835);
FORCEPROP 1 LASTPIN (3250 2825) BN 0
J 0
(3238 2833);
DISPLAY 0.680851 (3238 2833);
PAINT GREEN (3238 2833);
FORCEPROP 2 LAST CDS_LIB standard
J 0
(3300 2825);
PAINT MONO (3300 2825);
DISPLAY INVISIBLE (3300 2825);
FORCEPROP 1 LAST BODY_TYPE PLUMBING
J 0
(3300 2875);
DISPLAY 0.872340 (3300 2875);
PAINT GREEN (3300 2875);
DISPLAY INVISIBLE (3300 2875);
FORCEPROP 1 LAST HDL_TAP TRUE
J 0
(3625 2700);
DISPLAY 0.872340 (3625 2700);
DISPLAY INVISIBLE (3625 2700);
FORCEPROP 1 LAST PATH I79
J 0
(3298 2825);
DISPLAY 0.872340 (3298 2825);
PAINT GREEN (3298 2825);
DISPLAY INVISIBLE (3298 2825);
FORCEADD TAP..1
R 2
(-75 1825);
FORCEPROP 3 LASTPIN (-25 1825) SIG_NAME UPI_CPU0_CPU1_P2P2_DN<5>
J 0
(-15 1835);
DISPLAY 0.659574 (-15 1835);
PAINT MONO (-15 1835);
DISPLAY INVISIBLE (-15 1835);
FORCEPROP 1 LASTPIN (-25 1825) BN 5
J 2
(-13 1833);
DISPLAY 0.680851 (-13 1833);
PAINT GREEN (-13 1833);
FORCEPROP 2 LAST CDS_LIB standard
J 0
(-75 1825);
DISPLAY INVISIBLE (-75 1825);
FORCEPROP 1 LAST BODY_TYPE PLUMBING
J 2
(-75 1875);
DISPLAY 0.872340 (-75 1875);
PAINT GREEN (-75 1875);
DISPLAY INVISIBLE (-75 1875);
FORCEPROP 1 LAST HDL_TAP TRUE
J 2
(-400 1700);
DISPLAY 0.872340 (-400 1700);
DISPLAY INVISIBLE (-400 1700);
FORCEPROP 1 LAST PATH I8
J 2
(-73 1825);
DISPLAY 0.872340 (-73 1825);
PAINT GREEN (-73 1825);
DISPLAY INVISIBLE (-73 1825);
FORCEADD TAP..1
(3300 3025);
FORCEPROP 3 LASTPIN (3250 3025) SIG_NAME UPI_CPU1_CPU0_P2P2_DP<4>
J 0
(3260 3035);
DISPLAY 0.659574 (3260 3035);
PAINT MONO (3260 3035);
DISPLAY INVISIBLE (3260 3035);
FORCEPROP 1 LASTPIN (3250 3025) BN 4
J 0
(3238 3033);
DISPLAY 0.680851 (3238 3033);
PAINT GREEN (3238 3033);
FORCEPROP 2 LAST CDS_LIB standard
J 0
(3300 3025);
PAINT MONO (3300 3025);
DISPLAY INVISIBLE (3300 3025);
FORCEPROP 1 LAST BODY_TYPE PLUMBING
J 0
(3300 3075);
DISPLAY 0.872340 (3300 3075);
PAINT GREEN (3300 3075);
DISPLAY INVISIBLE (3300 3075);
FORCEPROP 1 LAST HDL_TAP TRUE
J 0
(3625 2900);
DISPLAY 0.872340 (3625 2900);
DISPLAY INVISIBLE (3625 2900);
FORCEPROP 1 LAST PATH I80
J 0
(3298 3025);
DISPLAY 0.872340 (3298 3025);
PAINT GREEN (3298 3025);
DISPLAY INVISIBLE (3298 3025);
FORCEADD TAP..1
(3300 3075);
FORCEPROP 3 LASTPIN (3250 3075) SIG_NAME UPI_CPU1_CPU0_P2P2_DP<5>
J 0
(3260 3085);
DISPLAY 0.659574 (3260 3085);
PAINT MONO (3260 3085);
DISPLAY INVISIBLE (3260 3085);
FORCEPROP 1 LASTPIN (3250 3075) BN 5
J 0
(3238 3083);
DISPLAY 0.680851 (3238 3083);
PAINT GREEN (3238 3083);
FORCEPROP 2 LAST CDS_LIB standard
J 0
(3300 3075);
PAINT MONO (3300 3075);
DISPLAY INVISIBLE (3300 3075);
FORCEPROP 1 LAST BODY_TYPE PLUMBING
J 0
(3300 3125);
DISPLAY 0.872340 (3300 3125);
PAINT GREEN (3300 3125);
DISPLAY INVISIBLE (3300 3125);
FORCEPROP 1 LAST HDL_TAP TRUE
J 0
(3625 2950);
DISPLAY 0.872340 (3625 2950);
DISPLAY INVISIBLE (3625 2950);
FORCEPROP 1 LAST PATH I81
J 0
(3298 3075);
DISPLAY 0.872340 (3298 3075);
PAINT GREEN (3298 3075);
DISPLAY INVISIBLE (3298 3075);
FORCEADD TAP..1
(3300 3225);
FORCEPROP 3 LASTPIN (3250 3225) SIG_NAME UPI_CPU1_CPU0_P2P2_DP<8>
J 0
(3260 3235);
DISPLAY 0.659574 (3260 3235);
PAINT MONO (3260 3235);
DISPLAY INVISIBLE (3260 3235);
FORCEPROP 1 LASTPIN (3250 3225) BN 8
J 0
(3238 3233);
DISPLAY 0.680851 (3238 3233);
PAINT GREEN (3238 3233);
FORCEPROP 2 LAST CDS_LIB standard
J 0
(3300 3225);
PAINT MONO (3300 3225);
DISPLAY INVISIBLE (3300 3225);
FORCEPROP 1 LAST BODY_TYPE PLUMBING
J 0
(3300 3275);
DISPLAY 0.872340 (3300 3275);
PAINT GREEN (3300 3275);
DISPLAY INVISIBLE (3300 3275);
FORCEPROP 1 LAST HDL_TAP TRUE
J 0
(3625 3100);
DISPLAY 0.872340 (3625 3100);
DISPLAY INVISIBLE (3625 3100);
FORCEPROP 1 LAST PATH I82
J 0
(3298 3225);
DISPLAY 0.872340 (3298 3225);
PAINT GREEN (3298 3225);
DISPLAY INVISIBLE (3298 3225);
FORCEADD TAP..1
(3300 3125);
FORCEPROP 3 LASTPIN (3250 3125) SIG_NAME UPI_CPU1_CPU0_P2P2_DP<6>
J 0
(3260 3135);
DISPLAY 0.659574 (3260 3135);
PAINT MONO (3260 3135);
DISPLAY INVISIBLE (3260 3135);
FORCEPROP 1 LASTPIN (3250 3125) BN 6
J 0
(3238 3133);
DISPLAY 0.680851 (3238 3133);
PAINT GREEN (3238 3133);
FORCEPROP 2 LAST CDS_LIB standard
J 0
(3300 3125);
PAINT MONO (3300 3125);
DISPLAY INVISIBLE (3300 3125);
FORCEPROP 1 LAST BODY_TYPE PLUMBING
J 0
(3300 3175);
DISPLAY 0.872340 (3300 3175);
PAINT GREEN (3300 3175);
DISPLAY INVISIBLE (3300 3175);
FORCEPROP 1 LAST HDL_TAP TRUE
J 0
(3625 3000);
DISPLAY 0.872340 (3625 3000);
DISPLAY INVISIBLE (3625 3000);
FORCEPROP 1 LAST PATH I83
J 0
(3298 3125);
DISPLAY 0.872340 (3298 3125);
PAINT GREEN (3298 3125);
DISPLAY INVISIBLE (3298 3125);
FORCEADD TAP..1
(3300 3175);
FORCEPROP 3 LASTPIN (3250 3175) SIG_NAME UPI_CPU1_CPU0_P2P2_DP<7>
J 0
(3260 3185);
DISPLAY 0.659574 (3260 3185);
PAINT MONO (3260 3185);
DISPLAY INVISIBLE (3260 3185);
FORCEPROP 1 LASTPIN (3250 3175) BN 7
J 0
(3238 3183);
DISPLAY 0.680851 (3238 3183);
PAINT GREEN (3238 3183);
FORCEPROP 2 LAST CDS_LIB standard
J 0
(3300 3175);
PAINT MONO (3300 3175);
DISPLAY INVISIBLE (3300 3175);
FORCEPROP 1 LAST BODY_TYPE PLUMBING
J 0
(3300 3225);
DISPLAY 0.872340 (3300 3225);
PAINT GREEN (3300 3225);
DISPLAY INVISIBLE (3300 3225);
FORCEPROP 1 LAST HDL_TAP TRUE
J 0
(3625 3050);
DISPLAY 0.872340 (3625 3050);
DISPLAY INVISIBLE (3625 3050);
FORCEPROP 1 LAST PATH I84
J 0
(3298 3175);
DISPLAY 0.872340 (3298 3175);
PAINT GREEN (3298 3175);
DISPLAY INVISIBLE (3298 3175);
FORCEADD TAP..1
(3300 3325);
FORCEPROP 3 LASTPIN (3250 3325) SIG_NAME UPI_CPU1_CPU0_P2P2_DP<10>
J 0
(3260 3335);
DISPLAY 0.659574 (3260 3335);
PAINT MONO (3260 3335);
DISPLAY INVISIBLE (3260 3335);
FORCEPROP 1 LASTPIN (3250 3325) BN 10
J 0
(3238 3333);
DISPLAY 0.680851 (3238 3333);
PAINT GREEN (3238 3333);
FORCEPROP 2 LAST CDS_LIB standard
J 0
(3300 3325);
PAINT MONO (3300 3325);
DISPLAY INVISIBLE (3300 3325);
FORCEPROP 1 LAST BODY_TYPE PLUMBING
J 0
(3300 3375);
DISPLAY 0.872340 (3300 3375);
PAINT GREEN (3300 3375);
DISPLAY INVISIBLE (3300 3375);
FORCEPROP 1 LAST HDL_TAP TRUE
J 0
(3625 3200);
DISPLAY 0.872340 (3625 3200);
DISPLAY INVISIBLE (3625 3200);
FORCEPROP 1 LAST PATH I85
J 0
(3298 3325);
DISPLAY 0.872340 (3298 3325);
PAINT GREEN (3298 3325);
DISPLAY INVISIBLE (3298 3325);
FORCEADD TAP..1
(3300 3275);
FORCEPROP 3 LASTPIN (3250 3275) SIG_NAME UPI_CPU1_CPU0_P2P2_DP<9>
J 0
(3260 3285);
DISPLAY 0.659574 (3260 3285);
PAINT MONO (3260 3285);
DISPLAY INVISIBLE (3260 3285);
FORCEPROP 1 LASTPIN (3250 3275) BN 9
J 0
(3238 3283);
DISPLAY 0.680851 (3238 3283);
PAINT GREEN (3238 3283);
FORCEPROP 2 LAST CDS_LIB standard
J 0
(3300 3275);
PAINT MONO (3300 3275);
DISPLAY INVISIBLE (3300 3275);
FORCEPROP 1 LAST BODY_TYPE PLUMBING
J 0
(3300 3325);
DISPLAY 0.872340 (3300 3325);
PAINT GREEN (3300 3325);
DISPLAY INVISIBLE (3300 3325);
FORCEPROP 1 LAST HDL_TAP TRUE
J 0
(3625 3150);
DISPLAY 0.872340 (3625 3150);
DISPLAY INVISIBLE (3625 3150);
FORCEPROP 1 LAST PATH I86
J 0
(3298 3275);
DISPLAY 0.872340 (3298 3275);
PAINT GREEN (3298 3275);
DISPLAY INVISIBLE (3298 3275);
FORCEADD TAP..1
(3300 3375);
FORCEPROP 3 LASTPIN (3250 3375) SIG_NAME UPI_CPU1_CPU0_P2P2_DP<11>
J 0
(3260 3385);
DISPLAY 0.659574 (3260 3385);
PAINT MONO (3260 3385);
DISPLAY INVISIBLE (3260 3385);
FORCEPROP 1 LASTPIN (3250 3375) BN 11
J 0
(3238 3383);
DISPLAY 0.680851 (3238 3383);
PAINT GREEN (3238 3383);
FORCEPROP 2 LAST CDS_LIB standard
J 0
(3300 3375);
PAINT MONO (3300 3375);
DISPLAY INVISIBLE (3300 3375);
FORCEPROP 1 LAST BODY_TYPE PLUMBING
J 0
(3300 3425);
DISPLAY 0.872340 (3300 3425);
PAINT GREEN (3300 3425);
DISPLAY INVISIBLE (3300 3425);
FORCEPROP 1 LAST HDL_TAP TRUE
J 0
(3625 3250);
DISPLAY 0.872340 (3625 3250);
DISPLAY INVISIBLE (3625 3250);
FORCEPROP 1 LAST PATH I87
J 0
(3298 3375);
DISPLAY 0.872340 (3298 3375);
PAINT GREEN (3298 3375);
DISPLAY INVISIBLE (3298 3375);
FORCEADD TAP..1
(3300 3475);
FORCEPROP 3 LASTPIN (3250 3475) SIG_NAME UPI_CPU1_CPU0_P2P2_DP<13>
J 0
(3260 3485);
DISPLAY 0.659574 (3260 3485);
PAINT MONO (3260 3485);
DISPLAY INVISIBLE (3260 3485);
FORCEPROP 1 LASTPIN (3250 3475) BN 13
J 0
(3238 3483);
DISPLAY 0.680851 (3238 3483);
PAINT GREEN (3238 3483);
FORCEPROP 2 LAST CDS_LIB standard
J 0
(3300 3475);
PAINT MONO (3300 3475);
DISPLAY INVISIBLE (3300 3475);
FORCEPROP 1 LAST BODY_TYPE PLUMBING
J 0
(3300 3525);
DISPLAY 0.872340 (3300 3525);
PAINT GREEN (3300 3525);
DISPLAY INVISIBLE (3300 3525);
FORCEPROP 1 LAST HDL_TAP TRUE
J 0
(3625 3350);
DISPLAY 0.872340 (3625 3350);
DISPLAY INVISIBLE (3625 3350);
FORCEPROP 1 LAST PATH I88
J 0
(3298 3475);
DISPLAY 0.872340 (3298 3475);
PAINT GREEN (3298 3475);
DISPLAY INVISIBLE (3298 3475);
FORCEADD TAP..1
(3300 3425);
FORCEPROP 3 LASTPIN (3250 3425) SIG_NAME UPI_CPU1_CPU0_P2P2_DP<12>
J 0
(3260 3435);
DISPLAY 0.659574 (3260 3435);
PAINT MONO (3260 3435);
DISPLAY INVISIBLE (3260 3435);
FORCEPROP 1 LASTPIN (3250 3425) BN 12
J 0
(3238 3433);
DISPLAY 0.680851 (3238 3433);
PAINT GREEN (3238 3433);
FORCEPROP 2 LAST CDS_LIB standard
J 0
(3300 3425);
PAINT MONO (3300 3425);
DISPLAY INVISIBLE (3300 3425);
FORCEPROP 1 LAST BODY_TYPE PLUMBING
J 0
(3300 3475);
DISPLAY 0.872340 (3300 3475);
PAINT GREEN (3300 3475);
DISPLAY INVISIBLE (3300 3475);
FORCEPROP 1 LAST HDL_TAP TRUE
J 0
(3625 3300);
DISPLAY 0.872340 (3625 3300);
DISPLAY INVISIBLE (3625 3300);
FORCEPROP 1 LAST PATH I89
J 0
(3298 3425);
DISPLAY 0.872340 (3298 3425);
PAINT GREEN (3298 3425);
DISPLAY INVISIBLE (3298 3425);
FORCEADD TAP..1
R 2
(-75 1925);
FORCEPROP 3 LASTPIN (-25 1925) SIG_NAME UPI_CPU0_CPU1_P2P2_DN<7>
J 0
(-15 1935);
DISPLAY 0.659574 (-15 1935);
PAINT MONO (-15 1935);
DISPLAY INVISIBLE (-15 1935);
FORCEPROP 1 LASTPIN (-25 1925) BN 7
J 2
(-13 1933);
DISPLAY 0.680851 (-13 1933);
PAINT GREEN (-13 1933);
FORCEPROP 2 LAST CDS_LIB standard
J 0
(-75 1925);
DISPLAY INVISIBLE (-75 1925);
FORCEPROP 1 LAST BODY_TYPE PLUMBING
J 2
(-75 1975);
DISPLAY 0.872340 (-75 1975);
PAINT GREEN (-75 1975);
DISPLAY INVISIBLE (-75 1975);
FORCEPROP 1 LAST HDL_TAP TRUE
J 2
(-400 1800);
DISPLAY 0.872340 (-400 1800);
DISPLAY INVISIBLE (-400 1800);
FORCEPROP 1 LAST PATH I9
J 2
(-73 1925);
DISPLAY 0.872340 (-73 1925);
PAINT GREEN (-73 1925);
DISPLAY INVISIBLE (-73 1925);
FORCEADD TAP..1
(3300 3575);
FORCEPROP 3 LASTPIN (3250 3575) SIG_NAME UPI_CPU1_CPU0_P2P2_DP<15>
J 0
(3260 3585);
DISPLAY 0.659574 (3260 3585);
PAINT MONO (3260 3585);
DISPLAY INVISIBLE (3260 3585);
FORCEPROP 1 LASTPIN (3250 3575) BN 15
J 0
(3238 3583);
DISPLAY 0.680851 (3238 3583);
PAINT GREEN (3238 3583);
FORCEPROP 2 LAST CDS_LIB standard
J 0
(3300 3575);
PAINT MONO (3300 3575);
DISPLAY INVISIBLE (3300 3575);
FORCEPROP 1 LAST BODY_TYPE PLUMBING
J 0
(3300 3625);
DISPLAY 0.872340 (3300 3625);
PAINT GREEN (3300 3625);
DISPLAY INVISIBLE (3300 3625);
FORCEPROP 1 LAST HDL_TAP TRUE
J 0
(3625 3450);
DISPLAY 0.872340 (3625 3450);
DISPLAY INVISIBLE (3625 3450);
FORCEPROP 1 LAST PATH I90
J 0
(3298 3575);
DISPLAY 0.872340 (3298 3575);
PAINT GREEN (3298 3575);
DISPLAY INVISIBLE (3298 3575);
FORCEADD TAP..1
(3300 3525);
FORCEPROP 3 LASTPIN (3250 3525) SIG_NAME UPI_CPU1_CPU0_P2P2_DP<14>
J 0
(3260 3535);
DISPLAY 0.659574 (3260 3535);
PAINT MONO (3260 3535);
DISPLAY INVISIBLE (3260 3535);
FORCEPROP 1 LASTPIN (3250 3525) BN 14
J 0
(3238 3533);
DISPLAY 0.680851 (3238 3533);
PAINT GREEN (3238 3533);
FORCEPROP 2 LAST CDS_LIB standard
J 0
(3300 3525);
PAINT MONO (3300 3525);
DISPLAY INVISIBLE (3300 3525);
FORCEPROP 1 LAST BODY_TYPE PLUMBING
J 0
(3300 3575);
DISPLAY 0.872340 (3300 3575);
PAINT GREEN (3300 3575);
DISPLAY INVISIBLE (3300 3575);
FORCEPROP 1 LAST HDL_TAP TRUE
J 0
(3625 3400);
DISPLAY 0.872340 (3625 3400);
DISPLAY INVISIBLE (3625 3400);
FORCEPROP 1 LAST PATH I91
J 0
(3298 3525);
DISPLAY 0.872340 (3298 3525);
PAINT GREEN (3298 3525);
DISPLAY INVISIBLE (3298 3525);
FORCEADD TAP..1
(3300 3625);
FORCEPROP 3 LASTPIN (3250 3625) SIG_NAME UPI_CPU1_CPU0_P2P2_DP<16>
J 0
(3260 3635);
DISPLAY 0.659574 (3260 3635);
PAINT MONO (3260 3635);
DISPLAY INVISIBLE (3260 3635);
FORCEPROP 1 LASTPIN (3250 3625) BN 16
J 0
(3238 3633);
DISPLAY 0.680851 (3238 3633);
PAINT GREEN (3238 3633);
FORCEPROP 2 LAST CDS_LIB standard
J 0
(3300 3625);
PAINT MONO (3300 3625);
DISPLAY INVISIBLE (3300 3625);
FORCEPROP 1 LAST BODY_TYPE PLUMBING
J 0
(3300 3675);
DISPLAY 0.872340 (3300 3675);
PAINT GREEN (3300 3675);
DISPLAY INVISIBLE (3300 3675);
FORCEPROP 1 LAST HDL_TAP TRUE
J 0
(3625 3500);
DISPLAY 0.872340 (3625 3500);
DISPLAY INVISIBLE (3625 3500);
FORCEPROP 1 LAST PATH I92
J 0
(3298 3625);
DISPLAY 0.872340 (3298 3625);
PAINT GREEN (3298 3625);
DISPLAY INVISIBLE (3298 3625);
FORCEADD TAP..1
(3300 3725);
FORCEPROP 3 LASTPIN (3250 3725) SIG_NAME UPI_CPU1_CPU0_P2P2_DP<18>
J 0
(3260 3735);
DISPLAY 0.659574 (3260 3735);
PAINT MONO (3260 3735);
DISPLAY INVISIBLE (3260 3735);
FORCEPROP 1 LASTPIN (3250 3725) BN 18
J 0
(3238 3733);
DISPLAY 0.680851 (3238 3733);
PAINT GREEN (3238 3733);
FORCEPROP 2 LAST CDS_LIB standard
J 0
(3300 3725);
DISPLAY INVISIBLE (3300 3725);
FORCEPROP 1 LAST BODY_TYPE PLUMBING
J 0
(3300 3775);
DISPLAY 0.872340 (3300 3775);
PAINT GREEN (3300 3775);
DISPLAY INVISIBLE (3300 3775);
FORCEPROP 1 LAST HDL_TAP TRUE
J 0
(3625 3600);
DISPLAY 0.872340 (3625 3600);
DISPLAY INVISIBLE (3625 3600);
FORCEPROP 1 LAST PATH I93
J 0
(3298 3725);
DISPLAY 0.872340 (3298 3725);
PAINT GREEN (3298 3725);
DISPLAY INVISIBLE (3298 3725);
FORCEADD TAP..1
(3300 3675);
FORCEPROP 3 LASTPIN (3250 3675) SIG_NAME UPI_CPU1_CPU0_P2P2_DP<17>
J 0
(3260 3685);
DISPLAY 0.659574 (3260 3685);
PAINT MONO (3260 3685);
DISPLAY INVISIBLE (3260 3685);
FORCEPROP 1 LASTPIN (3250 3675) BN 17
J 0
(3238 3683);
DISPLAY 0.680851 (3238 3683);
PAINT GREEN (3238 3683);
FORCEPROP 2 LAST CDS_LIB standard
J 0
(3300 3675);
DISPLAY INVISIBLE (3300 3675);
FORCEPROP 1 LAST BODY_TYPE PLUMBING
J 0
(3300 3725);
DISPLAY 0.872340 (3300 3725);
PAINT GREEN (3300 3725);
DISPLAY INVISIBLE (3300 3725);
FORCEPROP 1 LAST HDL_TAP TRUE
J 0
(3625 3550);
DISPLAY 0.872340 (3625 3550);
DISPLAY INVISIBLE (3625 3550);
FORCEPROP 1 LAST PATH I94
J 0
(3298 3675);
DISPLAY 0.872340 (3298 3675);
PAINT GREEN (3298 3675);
DISPLAY INVISIBLE (3298 3675);
FORCEADD TAP..1
(3300 3775);
FORCEPROP 3 LASTPIN (3250 3775) SIG_NAME UPI_CPU1_CPU0_P2P2_DP<19>
J 0
(3260 3785);
DISPLAY 0.659574 (3260 3785);
PAINT MONO (3260 3785);
DISPLAY INVISIBLE (3260 3785);
FORCEPROP 1 LASTPIN (3250 3775) BN 19
J 0
(3238 3783);
DISPLAY 0.680851 (3238 3783);
PAINT GREEN (3238 3783);
FORCEPROP 2 LAST CDS_LIB standard
J 0
(3300 3775);
DISPLAY INVISIBLE (3300 3775);
FORCEPROP 1 LAST BODY_TYPE PLUMBING
J 0
(3300 3825);
DISPLAY 0.872340 (3300 3825);
PAINT GREEN (3300 3825);
DISPLAY INVISIBLE (3300 3825);
FORCEPROP 1 LAST HDL_TAP TRUE
J 0
(3625 3650);
DISPLAY 0.872340 (3625 3650);
DISPLAY INVISIBLE (3625 3650);
FORCEPROP 1 LAST PATH I95
J 0
(3298 3775);
DISPLAY 0.872340 (3298 3775);
PAINT GREEN (3298 3775);
DISPLAY INVISIBLE (3298 3775);
FORCEADD TAP..1
(3300 3825);
FORCEPROP 3 LASTPIN (3250 3825) SIG_NAME UPI_CPU1_CPU0_P2P2_DP<20>
J 0
(3260 3835);
DISPLAY 0.659574 (3260 3835);
PAINT MONO (3260 3835);
DISPLAY INVISIBLE (3260 3835);
FORCEPROP 1 LASTPIN (3250 3825) BN 20
J 0
(3238 3833);
DISPLAY 0.680851 (3238 3833);
PAINT GREEN (3238 3833);
FORCEPROP 2 LAST CDS_LIB standard
J 0
(3300 3825);
DISPLAY INVISIBLE (3300 3825);
FORCEPROP 1 LAST BODY_TYPE PLUMBING
J 0
(3300 3875);
DISPLAY 0.872340 (3300 3875);
PAINT GREEN (3300 3875);
DISPLAY INVISIBLE (3300 3875);
FORCEPROP 1 LAST HDL_TAP TRUE
J 0
(3625 3700);
DISPLAY 0.872340 (3625 3700);
DISPLAY INVISIBLE (3625 3700);
FORCEPROP 1 LAST PATH I96
J 0
(3298 3825);
DISPLAY 0.872340 (3298 3825);
PAINT GREEN (3298 3825);
DISPLAY INVISIBLE (3298 3825);
FORCEADD TAP..1
(3300 3875);
FORCEPROP 3 LASTPIN (3250 3875) SIG_NAME UPI_CPU1_CPU0_P2P2_DP<21>
J 0
(3260 3885);
DISPLAY 0.659574 (3260 3885);
PAINT MONO (3260 3885);
DISPLAY INVISIBLE (3260 3885);
FORCEPROP 1 LASTPIN (3250 3875) BN 21
J 0
(3238 3883);
DISPLAY 0.680851 (3238 3883);
PAINT GREEN (3238 3883);
FORCEPROP 2 LAST CDS_LIB standard
J 0
(3300 3875);
DISPLAY INVISIBLE (3300 3875);
FORCEPROP 1 LAST BODY_TYPE PLUMBING
J 0
(3300 3925);
DISPLAY 0.872340 (3300 3925);
PAINT GREEN (3300 3925);
DISPLAY INVISIBLE (3300 3925);
FORCEPROP 1 LAST HDL_TAP TRUE
J 0
(3625 3750);
DISPLAY 0.872340 (3625 3750);
DISPLAY INVISIBLE (3625 3750);
FORCEPROP 1 LAST PATH I97
J 0
(3298 3875);
DISPLAY 0.872340 (3298 3875);
PAINT GREEN (3298 3875);
DISPLAY INVISIBLE (3298 3875);
FORCEADD TAP..1
(3300 3925);
FORCEPROP 3 LASTPIN (3250 3925) SIG_NAME UPI_CPU1_CPU0_P2P2_DP<22>
J 0
(3260 3935);
DISPLAY 0.659574 (3260 3935);
PAINT MONO (3260 3935);
DISPLAY INVISIBLE (3260 3935);
FORCEPROP 1 LASTPIN (3250 3925) BN 22
J 0
(3238 3933);
DISPLAY 0.680851 (3238 3933);
PAINT GREEN (3238 3933);
FORCEPROP 2 LAST CDS_LIB standard
J 0
(3300 3925);
DISPLAY INVISIBLE (3300 3925);
FORCEPROP 1 LAST BODY_TYPE PLUMBING
J 0
(3300 3975);
DISPLAY 0.872340 (3300 3975);
PAINT GREEN (3300 3975);
DISPLAY INVISIBLE (3300 3975);
FORCEPROP 1 LAST HDL_TAP TRUE
J 0
(3625 3800);
DISPLAY 0.872340 (3625 3800);
DISPLAY INVISIBLE (3625 3800);
FORCEPROP 1 LAST PATH I98
J 0
(3298 3925);
DISPLAY 0.872340 (3298 3925);
PAINT GREEN (3298 3925);
DISPLAY INVISIBLE (3298 3925);
FORCEADD TAP..1
(3300 3975);
FORCEPROP 3 LASTPIN (3250 3975) SIG_NAME UPI_CPU1_CPU0_P2P2_DP<23>
J 0
(3260 3985);
DISPLAY 0.659574 (3260 3985);
PAINT MONO (3260 3985);
DISPLAY INVISIBLE (3260 3985);
FORCEPROP 1 LASTPIN (3250 3975) BN 23
J 0
(3238 3983);
DISPLAY 0.680851 (3238 3983);
PAINT GREEN (3238 3983);
FORCEPROP 2 LAST CDS_LIB standard
J 0
(3300 3975);
DISPLAY INVISIBLE (3300 3975);
FORCEPROP 1 LAST BODY_TYPE PLUMBING
J 0
(3300 4025);
DISPLAY 0.872340 (3300 4025);
PAINT GREEN (3300 4025);
DISPLAY INVISIBLE (3300 4025);
FORCEPROP 1 LAST HDL_TAP TRUE
J 0
(3625 3850);
DISPLAY 0.872340 (3625 3850);
DISPLAY INVISIBLE (3625 3850);
FORCEPROP 1 LAST PATH I99
J 0
(3298 3975);
DISPLAY 0.872340 (3298 3975);
PAINT GREEN (3298 3975);
DISPLAY INVISIBLE (3298 3975);
FORCEADD QUANTA_TITLE_BLOCK_C..1
(6225 -1525);
FORCEPROP 0 LAST CDS_CON_LAST_MODIFIED Fri Aug 25 14:00:46 2023
J 0
(4340 -1510);
PAINT MONO (4340 -1510);
DISPLAY INVISIBLE (4340 -1510);
FORCEPROP 1 LAST CUSTOM_TXT_CDS <CON_LAST_MODIFIED>
J 0
(4340 -1510);
DISPLAY 0.978723 (4340 -1510);
FORCEPROP 2 LAST CUSTOM_TXT_CDS <XR_PAGE_TITLE>
J 0
(-1665 3725);
DISPLAY 0.638298 (-1665 3725);
PAINT PINK (-1665 3725);
DISPLAY INVISIBLE (-1665 3725);
FORCEPROP 2 LAST CUSTOM_TXT_CDS <Q_NUMBER>
J 0
(4822 -1422);
DISPLAY 1.212766 (4822 -1422);
FORCEPROP 1 LAST CUSTOM_TXT_CDS <NAME_2>
J 0
(3050 -1475);
FORCEPROP 1 LAST CUSTOM_TXT_CDS <NAME_1>
J 0
(3050 -1350);
FORCEPROP 1 LAST CUSTOM_TXT_CDS <Q_PROJ>
J 0
(3843 -1423);
DISPLAY 1.212766 (3843 -1423);
FORCEPROP 1 LAST CUSTOM_TXT_CDS <Q_REV>
J 0
(6041 -1422);
DISPLAY 1.212766 (6041 -1422);
FORCEPROP 1 LAST CUSTOM_TXT_CDS <CON_PAGE_NUM> OF <CON_TOTAL_PAGES>
J 0
(5779 -1507);
DISPLAY 0.978723 (5779 -1507);
FORCEPROP 1 LAST Q_TITLE SPR CPU1 - UPI2 (22 OF 30)
J 0
(-3141 -1499);
DISPLAY 1.957447 (-3141 -1499);
PAINT GREEN (-3141 -1499);
FORCEPROP 1 LAST Q_DEPT 
J 1
(2462 -1476);
DISPLAY 1.957447 (2462 -1476);
PAINT GREEN (2462 -1476);
FORCEPROP 1 LAST COMMENT_BODY TRUE
J 0
(6237 -1538);
DISPLAY 0.978723 (6237 -1538);
PAINT GREEN (6237 -1538);
DISPLAY INVISIBLE (6237 -1538);
FORCEPROP 2 LAST CDS_XR_PAGE_TITLE CR-65 : @S9S_MB_2U_LIB.S9S_MB_2U(SCH_1):PAGE65
J 0
(-1665 3725);
DISPLAY 0.638298 (-1665 3725);
PAINT PINK (-1665 3725);
DISPLAY INVISIBLE (-1665 3725);
FORCEPROP 2 LAST CDS_LIB pure_quanta
J 0
(6225 -1525);
PAINT MONO (6225 -1525);
DISPLAY INVISIBLE (6225 -1525);
FORCEPROP 1 LAST CDS_LMAN_SYM_OUTLINE -9475,6775,100,-125
J 0
(6225 -1525);
DISPLAY 0.468085 (6225 -1525);
PAINT GREEN (6225 -1525);
DISPLAY INVISIBLE (6225 -1525);
FORCEPROP 2 LAST PAGE_BORDER TRUE
J 0
(-1665 3725);
DISPLAY 0.638298 (-1665 3725);
PAINT PINK (-1665 3725);
DISPLAY INVISIBLE (-1665 3725);
WIRE 17 -1 (3350 2850)(3350 2900);
WIRE 17 -1 (3350 2900)(3350 2950);
WIRE 17 -1 (3350 2950)(3350 3000);
WIRE 17 -1 (3350 3000)(3350 3050);
WIRE 17 -1 (3350 3050)(3350 3100);
WIRE 17 -1 (3350 3100)(3350 3150);
WIRE 17 -1 (3350 3150)(3350 3200);
WIRE 17 -1 (3350 3200)(3350 3250);
WIRE 17 -1 (3350 3250)(3350 3300);
WIRE 17 -1 (3350 3300)(3350 3350);
WIRE 17 -1 (3350 3350)(3350 3400);
WIRE 17 -1 (3350 3400)(3350 3450);
WIRE 17 -1 (3350 3450)(3350 3500);
WIRE 17 -1 (3350 3500)(3350 3550);
WIRE 17 -1 (3350 3550)(3350 3600);
WIRE 17 -1 (3350 3600)(3350 3650);
WIRE 17 -1 (3350 3650)(3350 3700);
WIRE 17 -1 (3350 3700)(3350 3750);
WIRE 17 -1 (3350 3750)(3350 3800);
WIRE 17 -1 (3350 3800)(3350 3850);
WIRE 17 -1 (3350 3850)(3350 3900);
WIRE 17 -1 (3350 3900)(3350 3950);
WIRE 17 -1 (3350 3950)(3350 4000);
WIRE 17 -1 (3350 4000)(4450 4000);
FORCEPROP 2 LAST SIG_NAME UPI_CPU1_CPU0_P2P2_DP<23:0>
J 0
(3490 4010);
DISPLAY 0.680851 (3490 4010);
PAINT WHITE (3490 4010);
WIRE 17 -1 (3350 1600)(3350 1650);
WIRE 17 -1 (3350 1650)(3350 1700);
WIRE 17 -1 (3350 1700)(3350 1750);
WIRE 17 -1 (3350 1750)(3350 1800);
WIRE 17 -1 (3350 1800)(3350 1850);
WIRE 17 -1 (3350 1850)(3350 1900);
WIRE 17 -1 (3350 1900)(3350 1950);
WIRE 17 -1 (3350 1950)(3350 2000);
WIRE 17 -1 (3350 2050)(3350 2000);
WIRE 17 -1 (3350 2050)(3350 2100);
WIRE 17 -1 (3350 2100)(3350 2150);
WIRE 17 -1 (3350 2150)(3350 2200);
WIRE 17 -1 (3350 2200)(3350 2250);
WIRE 17 -1 (3350 2250)(3350 2300);
WIRE 17 -1 (3350 2300)(3350 2350);
WIRE 17 -1 (3350 2350)(3350 2400);
WIRE 17 -1 (3350 2400)(3350 2450);
WIRE 17 -1 (3350 2450)(3350 2500);
WIRE 17 -1 (3350 2500)(3350 2550);
WIRE 17 -1 (3350 2550)(3350 2600);
WIRE 17 -1 (3350 2600)(3350 2650);
WIRE 17 -1 (3350 2650)(3350 2700);
WIRE 17 -1 (3350 2700)(3350 2750);
WIRE 17 -1 (3350 2750)(4450 2750);
FORCEPROP 2 LAST SIG_NAME UPI_CPU1_CPU0_P2P2_DN<23:0>
J 0
(3490 2760);
DISPLAY 0.680851 (3490 2760);
PAINT WHITE (3490 2760);
WIRE 17 -1 (-125 2850)(-125 2900);
WIRE 17 -1 (-125 2900)(-125 2950);
WIRE 17 -1 (-125 2950)(-125 3000);
WIRE 17 -1 (-125 3000)(-125 3050);
WIRE 17 -1 (-125 3050)(-125 3100);
WIRE 17 -1 (-125 3100)(-125 3150);
WIRE 17 -1 (-125 3150)(-125 3200);
WIRE 17 -1 (-125 3200)(-125 3250);
WIRE 17 -1 (-125 3250)(-125 3300);
WIRE 17 -1 (-125 3300)(-125 3350);
WIRE 17 -1 (-125 3350)(-125 3400);
WIRE 17 -1 (-125 3400)(-125 3450);
WIRE 17 -1 (-125 3450)(-125 3500);
WIRE 17 -1 (-125 3500)(-125 3550);
WIRE 17 -1 (-125 3550)(-125 3600);
WIRE 17 -1 (-125 3600)(-125 3650);
WIRE 17 -1 (-125 3650)(-125 3700);
WIRE 17 -1 (-125 3700)(-125 3750);
WIRE 17 -1 (-125 3750)(-125 3800);
WIRE 17 -1 (-125 3800)(-125 3850);
WIRE 17 -1 (-125 3850)(-125 3900);
WIRE 17 -1 (-125 3900)(-125 3950);
WIRE 17 -1 (-125 3950)(-125 4000);
WIRE 17 -1 (-1275 4000)(-125 4000);
FORCEPROP 2 LAST SIG_NAME UPI_CPU0_CPU1_P2P2_DP<23:0>
J 0
(-1160 4010);
DISPLAY 0.680851 (-1160 4010);
PAINT WHITE (-1160 4010);
WIRE 17 -1 (-125 1600)(-125 1650);
WIRE 17 -1 (-125 1650)(-125 1700);
WIRE 17 -1 (-125 1700)(-125 1750);
WIRE 17 -1 (-125 1750)(-125 1800);
WIRE 17 -1 (-125 1800)(-125 1850);
WIRE 17 -1 (-125 1850)(-125 1900);
WIRE 17 -1 (-125 1900)(-125 1950);
WIRE 17 -1 (-125 1950)(-125 2000);
WIRE 17 -1 (-125 2000)(-125 2050);
WIRE 17 -1 (-125 2050)(-125 2100);
WIRE 17 -1 (-125 2100)(-125 2150);
WIRE 17 -1 (-125 2150)(-125 2200);
WIRE 17 -1 (-125 2200)(-125 2250);
WIRE 17 -1 (-125 2250)(-125 2300);
WIRE 17 -1 (-125 2300)(-125 2350);
WIRE 17 -1 (-125 2350)(-125 2400);
WIRE 17 -1 (-125 2400)(-125 2450);
WIRE 17 -1 (-125 2450)(-125 2500);
WIRE 17 -1 (-125 2500)(-125 2550);
WIRE 17 -1 (-125 2550)(-125 2600);
WIRE 17 -1 (-125 2600)(-125 2650);
WIRE 17 -1 (-125 2650)(-125 2700);
WIRE 17 -1 (-125 2700)(-125 2750);
WIRE 17 -1 (-1275 2750)(-125 2750);
FORCEPROP 2 LAST SIG_NAME UPI_CPU0_CPU1_P2P2_DN<23:0>
J 0
(-1160 2760);
DISPLAY 0.680851 (-1160 2760);
PAINT WHITE (-1160 2760);
WIRE 16 -1 (-25 2725)(425 2725);
WIRE 16 -1 (-25 2675)(425 2675);
WIRE 16 -1 (-25 2625)(425 2625);
WIRE 16 -1 (-25 2575)(425 2575);
WIRE 16 -1 (-25 2525)(425 2525);
WIRE 16 -1 (-25 2475)(425 2475);
WIRE 16 -1 (-25 2425)(425 2425);
WIRE 16 -1 (-25 2375)(425 2375);
WIRE 16 -1 (-25 2325)(425 2325);
WIRE 16 -1 (-25 2275)(425 2275);
WIRE 16 -1 (-25 2225)(425 2225);
WIRE 16 -1 (-25 2175)(425 2175);
WIRE 16 -1 (-25 2125)(425 2125);
WIRE 16 -1 (-25 2075)(425 2075);
WIRE 16 -1 (-25 2025)(425 2025);
WIRE 16 -1 (-25 1975)(425 1975);
WIRE 16 -1 (-25 1925)(425 1925);
WIRE 16 -1 (-25 1875)(425 1875);
WIRE 16 -1 (-25 1825)(425 1825);
WIRE 16 -1 (-25 1775)(425 1775);
WIRE 16 -1 (-25 1725)(425 1725);
WIRE 16 -1 (-25 1675)(425 1675);
WIRE 16 -1 (-25 1625)(425 1625);
WIRE 16 -1 (-25 1575)(425 1575);
WIRE 16 -1 (-25 3975)(425 3975);
WIRE 16 -1 (-25 3925)(425 3925);
WIRE 16 -1 (-25 3875)(425 3875);
WIRE 16 -1 (-25 3825)(425 3825);
WIRE 16 -1 (-25 3775)(425 3775);
WIRE 16 -1 (-25 3725)(425 3725);
WIRE 16 -1 (-25 3675)(425 3675);
WIRE 16 -1 (-25 3625)(425 3625);
WIRE 16 -1 (-25 3575)(425 3575);
WIRE 16 -1 (-25 3525)(425 3525);
WIRE 16 -1 (-25 3475)(425 3475);
WIRE 16 -1 (-25 3425)(425 3425);
WIRE 16 -1 (-25 3375)(425 3375);
WIRE 16 -1 (-25 3325)(425 3325);
WIRE 16 -1 (-25 3275)(425 3275);
WIRE 16 -1 (-25 3225)(425 3225);
WIRE 16 -1 (-25 3175)(425 3175);
WIRE 16 -1 (-25 3125)(425 3125);
WIRE 16 -1 (-25 3075)(425 3075);
WIRE 16 -1 (-25 3025)(425 3025);
WIRE 16 -1 (-25 2975)(425 2975);
WIRE 16 -1 (-25 2925)(425 2925);
WIRE 16 -1 (-25 2875)(425 2875);
WIRE 16 -1 (-25 2825)(425 2825);
WIRE 16 -1 (2825 2725)(3250 2725);
WIRE 16 -1 (2825 2675)(3250 2675);
WIRE 16 -1 (2825 2625)(3250 2625);
WIRE 16 -1 (2825 2575)(3250 2575);
WIRE 16 -1 (2825 2525)(3250 2525);
WIRE 16 -1 (2825 2475)(3250 2475);
WIRE 16 -1 (2825 2425)(3250 2425);
WIRE 16 -1 (2825 2375)(3250 2375);
WIRE 16 -1 (2825 2325)(3250 2325);
WIRE 16 -1 (2825 2275)(3250 2275);
WIRE 16 -1 (2825 2225)(3250 2225);
WIRE 16 -1 (2825 2175)(3250 2175);
WIRE 16 -1 (2825 2125)(3250 2125);
WIRE 16 -1 (2825 2075)(3250 2075);
WIRE 16 -1 (2825 2025)(3250 2025);
WIRE 16 -1 (2825 1975)(3250 1975);
WIRE 16 -1 (2825 1925)(3250 1925);
WIRE 16 -1 (2825 1875)(3250 1875);
WIRE 16 -1 (2825 1825)(3250 1825);
WIRE 16 -1 (2825 1775)(3250 1775);
WIRE 16 -1 (2825 1725)(3250 1725);
WIRE 16 -1 (2825 1675)(3250 1675);
WIRE 16 -1 (2825 1625)(3250 1625);
WIRE 16 -1 (2825 1575)(3250 1575);
WIRE 16 -1 (2825 3975)(3250 3975);
WIRE 16 -1 (2825 3925)(3250 3925);
WIRE 16 -1 (2825 3875)(3250 3875);
WIRE 16 -1 (2825 3825)(3250 3825);
WIRE 16 -1 (2825 3775)(3250 3775);
WIRE 16 -1 (2825 3725)(3250 3725);
WIRE 16 -1 (2825 3675)(3250 3675);
WIRE 16 -1 (2825 3625)(3250 3625);
WIRE 16 -1 (2825 3575)(3250 3575);
WIRE 16 -1 (2825 3525)(3250 3525);
WIRE 16 -1 (2825 3475)(3250 3475);
WIRE 16 -1 (2825 3425)(3250 3425);
WIRE 16 -1 (2825 3375)(3250 3375);
WIRE 16 -1 (2825 3325)(3250 3325);
WIRE 16 -1 (2825 3275)(3250 3275);
WIRE 16 -1 (2825 3225)(3250 3225);
WIRE 16 -1 (2825 3175)(3250 3175);
WIRE 16 -1 (2825 3125)(3250 3125);
WIRE 16 -1 (2825 3075)(3250 3075);
WIRE 16 -1 (2825 3025)(3250 3025);
WIRE 16 -1 (2825 2975)(3250 2975);
WIRE 16 -1 (2825 2925)(3250 2925);
WIRE 16 -1 (2825 2875)(3250 2875);
WIRE 16 -1 (2825 2825)(3250 2825);
QUIT
